STUFF LIST - 1  
2D2R2F-GP_SMD-RG1-2D2R2F-GP,64A                          RTI1            
2D2R2F-GP_SMD-RG1-2D2R2F-GP,64A                          RTI3            
2D2R2F-GP_SMD-RG1-2D2R2F-GP,64A                          RTI5            
2D2R2F-GP_SMD-RG1-2D2R2F-GP,64A                          RTI8            
2D2R2F-GP_SMD-RG1-2D2R2F-GP,64A                          RTI9            
2D2R2F-GP_SMD-RG1-2D2R2F-GP,64A                          RTI11           
2D2R2F-GP_SMD-RG1-2D2R2F-GP,64A                          RTI14           
2D2R2F-GP_SMD-RG1-2D2R2F-GP,64A                          RTI15           
2D2R2F-GP_SMD-RG1-2D2R2F-GP,64A                          RTI17           
2D2R2F-GP_SMD-RG1-2D2R2F-GP,64A                          RTI19           
2D2R2F-GP_SMD-RG1-2D2R2F-GP,64A                          RTI21           
2D2R2F-GP_SMD-RG1-2D2R2F-GP,64A                          RTI23           
2D2R2F-GP_SMD-RG1-2D2R2F-GP,64A                          RTI25           
2D2R2F-GP_SMD-RG1-2D2R2F-GP,64A                          RTI28           
2D2R2F-GP_SMD-RG1-2D2R2F-GP,64A                          RTI30           
2D2R2F-GP_SMD-RG1-2D2R2F-GP,64A                          RTI31           
2D2R2F-GP_SMD-RG1-2D2R2F-GP,64A                          RTI33           
2D2R2F-GP_SMD-RG1-2D2R2F-GP,64A                          RTI36           
2D2R2F-GP_SMD-RG1-2D2R2F-GP,64A                          RTI37           
2D2R2F-GP_SMD-RG1-2D2R2F-GP,64A                          RTI40           
2D2R2F-GP_SMD-RG1-2D2R2F-GP,64A                          RTI41           
2D2R2F-GP_SMD-RG1-2D2R2F-GP,64A                          RTI44           
2D2R2F-GP_SMD-RG1-2D2R2F-GP,64A                          RTI46           
2D2R2F-GP_SMD-RG1-2D2R2F-GP,64A                          RTI47           

----------------

3D01R5F-GP_SMD-RG5-3D01R5F-GP,A                          RTI2            
3D01R5F-GP_SMD-RG5-3D01R5F-GP,A                          RTI4            
3D01R5F-GP_SMD-RG5-3D01R5F-GP,A                          RTI6            
3D01R5F-GP_SMD-RG5-3D01R5F-GP,A                          RTI7            
3D01R5F-GP_SMD-RG5-3D01R5F-GP,A                          RTI10           
3D01R5F-GP_SMD-RG5-3D01R5F-GP,A                          RTI12           
3D01R5F-GP_SMD-RG5-3D01R5F-GP,A                          RTI13           
3D01R5F-GP_SMD-RG5-3D01R5F-GP,A                          RTI16           
3D01R5F-GP_SMD-RG5-3D01R5F-GP,A                          RTI18           
3D01R5F-GP_SMD-RG5-3D01R5F-GP,A                          RTI20           
3D01R5F-GP_SMD-RG5-3D01R5F-GP,A                          RTI22           
3D01R5F-GP_SMD-RG5-3D01R5F-GP,A                          RTI24           
3D01R5F-GP_SMD-RG5-3D01R5F-GP,A                          RTI26           
3D01R5F-GP_SMD-RG5-3D01R5F-GP,A                          RTI27           
3D01R5F-GP_SMD-RG5-3D01R5F-GP,A                          RTI29           
3D01R5F-GP_SMD-RG5-3D01R5F-GP,A                          RTI32           
3D01R5F-GP_SMD-RG5-3D01R5F-GP,A                          RTI34           
3D01R5F-GP_SMD-RG5-3D01R5F-GP,A                          RTI35           
3D01R5F-GP_SMD-RG5-3D01R5F-GP,A                          RTI38           
3D01R5F-GP_SMD-RG5-3D01R5F-GP,A                          RTI39           
3D01R5F-GP_SMD-RG5-3D01R5F-GP,A                          RTI42           
3D01R5F-GP_SMD-RG5-3D01R5F-GP,A                          RTI43           
3D01R5F-GP_SMD-RG5-3D01R5F-GP,A                          RTI45           
3D01R5F-GP_SMD-RG5-3D01R5F-GP,A                          RTI48           

----------------

74CBTLV1G125_SMLF-IC,C88177-00A C88177-001               U1M4            
74CBTLV1G125_SMLF-IC,C88177-00A C88177-001               U1M5            
74CBTLV1G125_SMLF-IC,C88177-00A C88177-001               U1M6            
74CBTLV1G125_SMLF-IC,C88177-00A C88177-001               U4R1            
74CBTLV1G125_SMLF-IC,C88177-00A C88177-001               U6M1            
74CBTLV1G125_SMLF-IC,C88177-00A C88177-001               U7D1            
74CBTLV1G125_SMLF-IC,C88177-00A C88177-001               U9A5            

----------------

ADC128D818_SM-IC,H63642-001 H63642-001               EU9G1           

----------------

ADM1085_SMT-IC,H46130-001 H46130-001               U7D3            

----------------

ADM1278_SM-IC,G99251-001 G99251-001               EU1D2           

----------------

ADM4073_SM-EMPTY,G12194-001 G12194-001               U1B3            
ADM4073_SM-EMPTY,G12194-001 G12194-001               U4C1            

----------------

ADM809_SMLF-IC,D23047-001-GND=A D23047-001               U1L3            
ADM809_SMLF-IC,D23047-001-GND=A D23047-001               U8E2            

----------------

AST1250_BGA-IC,G85138-002 G85138-002               U9F4            

----------------

AT24C64_SOICLF-IC,C47049-001-GA C47049-001               U8D4            

----------------

BATTERY_PLCLF-202168-001 202168-001               BT8G1           

----------------

CAPP_2626-270UF,16V,20%,OSCON,A A31228-047               C1B10           
CAPP_2626-270UF,16V,20%,OSCON,A A31228-047               C1C1            
CAPP_2626-270UF,16V,20%,OSCON,A A31228-047               C1C2            
CAPP_2626-270UF,16V,20%,OSCON,A A31228-047               C1E18           
CAPP_2626-270UF,16V,20%,OSCON,A A31228-047               C4C12           
CAPP_2626-270UF,16V,20%,OSCON,A A31228-047               C4D2            
CAPP_2626-270UF,16V,20%,OSCON,A A31228-047               C4E16           
CAPP_2626-270UF,16V,20%,OSCON,A A31228-047               C7A19           
CAPP_2626-270UF,16V,20%,OSCON,A A31228-047               C7G2            

----------------

CAPP_3018-470UF,2.5V,20%,ALUM,A 699013-049               C3L6            
CAPP_3018-470UF,2.5V,20%,ALUM,A 699013-049               C3L14           
CAPP_3018-470UF,2.5V,20%,ALUM,A 699013-049               C3N14           
CAPP_3018-470UF,2.5V,20%,ALUM,A 699013-049               C3N26           
CAPP_3018-470UF,2.5V,20%,ALUM,A 699013-049               C3N35           
CAPP_3018-470UF,2.5V,20%,ALUM,A 699013-049               C3N38           
CAPP_3018-470UF,2.5V,20%,ALUM,A 699013-049               C3R4            
CAPP_3018-470UF,2.5V,20%,ALUM,A 699013-049               C3U1            
CAPP_3018-470UF,2.5V,20%,ALUM,A 699013-049               C3U5            
CAPP_3018-470UF,2.5V,20%,ALUM,A 699013-049               C3U8            
CAPP_3018-470UF,2.5V,20%,ALUM,A 699013-049               C4C1            
CAPP_3018-470UF,2.5V,20%,ALUM,A 699013-049               C4E7            
CAPP_3018-470UF,2.5V,20%,ALUM,A 699013-049               C4E24           
CAPP_3018-470UF,2.5V,20%,ALUM,A 699013-049               C4L5            
CAPP_3018-470UF,2.5V,20%,ALUM,A 699013-049               C4R1            
CAPP_3018-470UF,2.5V,20%,ALUM,A 699013-049               C6A5            
CAPP_3018-470UF,2.5V,20%,ALUM,A 699013-049               C6N1            
CAPP_3018-470UF,2.5V,20%,ALUM,A 699013-049               C6N4            
CAPP_3018-470UF,2.5V,20%,ALUM,A 699013-049               C6N9            
CAPP_3018-470UF,2.5V,20%,ALUM,A 699013-049               C6P8            
CAPP_3018-470UF,2.5V,20%,ALUM,A 699013-049               C6P14           
CAPP_3018-470UF,2.5V,20%,ALUM,A 699013-049               C6P18           
CAPP_3018-470UF,2.5V,20%,ALUM,A 699013-049               C6P23           
CAPP_3018-470UF,2.5V,20%,ALUM,A 699013-049               C6R3            
CAPP_3018-470UF,2.5V,20%,ALUM,A 699013-049               C6R5            
CAPP_3018-470UF,2.5V,20%,ALUM,A 699013-049               C6R9            
CAPP_3018-470UF,2.5V,20%,ALUM,A 699013-049               C6R12           
CAPP_3018-470UF,2.5V,20%,ALUM,A 699013-049               C6R16           
CAPP_3018-470UF,2.5V,20%,ALUM,A 699013-049               C7G28           
CAPP_3018-470UF,2.5V,20%,ALUM,A 699013-049               C9L2            
CAPP_3018-470UF,2.5V,20%,ALUM,A 699013-049               C9L4            
CAPP_3018-470UF,2.5V,20%,ALUM,A 699013-049               C9L9            
CAPP_3018-470UF,2.5V,20%,ALUM,A 699013-049               C9L12           
CAPP_3018-470UF,2.5V,20%,ALUM,A 699013-049               C9N11           
CAPP_3018-470UF,2.5V,20%,ALUM,A 699013-049               C9N20           
CAPP_3018-470UF,2.5V,20%,ALUM,A 699013-049               C9N24           
CAPP_3018-470UF,2.5V,20%,ALUM,A 699013-049               C9P5            
CAPP_3018-470UF,2.5V,20%,ALUM,A 699013-049               C9P8            
CAPP_3018-470UF,2.5V,20%,ALUM,A 699013-049               C9P18           
CAPP_3018-470UF,2.5V,20%,ALUM,A 699013-049               C9P23           
CAPP_3018-470UF,2.5V,20%,ALUM,A 699013-049               C9R3            
CAPP_3018-470UF,2.5V,20%,ALUM,A 699013-049               C9R9            
CAPP_3018-470UF,2.5V,20%,ALUM,A 699013-049               C9T5            
CAPP_3018-470UF,2.5V,20%,ALUM,A 699013-049               C9U2            
CAPP_3018-470UF,2.5V,20%,ALUM,A 699013-049               C9U5            
CAPP_3018-470UF,2.5V,20%,ALUM,A 699013-049               C9U9            

----------------

CAPP_3018-470UF,6.3V,20%,POSCAA 724613-091               C8E4            
CAPP_3018-470UF,6.3V,20%,POSCAA 724613-091               C8F8            
CAPP_3018-470UF,6.3V,20%,POSCAA 724613-091               C8F14           

----------------

CAPP_3018-68UF,16V,20%,TANT,72A 724613-112               C1M5            
CAPP_3018-68UF,16V,20%,TANT,72A 724613-112               C1R23           
CAPP_3018-68UF,16V,20%,TANT,72A 724613-112               C3B6            
CAPP_3018-68UF,16V,20%,TANT,72A 724613-112               C3T3            
CAPP_3018-68UF,16V,20%,TANT,72A 724613-112               C3T6            
CAPP_3018-68UF,16V,20%,TANT,72A 724613-112               C3T13           
CAPP_3018-68UF,16V,20%,TANT,72A 724613-112               C3T15           
CAPP_3018-68UF,16V,20%,TANT,72A 724613-112               C4B14           
CAPP_3018-68UF,16V,20%,TANT,72A 724613-112               C4F4            
CAPP_3018-68UF,16V,20%,TANT,72A 724613-112               C4F5            
CAPP_3018-68UF,16V,20%,TANT,72A 724613-112               C4M6            
CAPP_3018-68UF,16V,20%,TANT,72A 724613-112               C4M7            
CAPP_3018-68UF,16V,20%,TANT,72A 724613-112               C6N5            
CAPP_3018-68UF,16V,20%,TANT,72A 724613-112               C7M6            
CAPP_3018-68UF,16V,20%,TANT,72A 724613-112               C9M3            
CAPP_3018-68UF,16V,20%,TANT,72A 724613-112               C9T3            

----------------

CAPP_4040LF-470UF,16V,20%,ALUMA A93539-036               C1B14           
CAPP_4040LF-470UF,16V,20%,ALUMA A93539-036               C1F7            
CAPP_4040LF-470UF,16V,20%,ALUMA A93539-036               C4B13           
CAPP_4040LF-470UF,16V,20%,ALUMA A93539-036               C4F6            

----------------

CAPP_7343-220UF,4V,20%,POSCAP,A 724613-067               C4F11           
CAPP_7343-220UF,4V,20%,POSCAP,A 724613-067               C4M1            
CAPP_7343-220UF,4V,20%,POSCAP,A 724613-067               C4T3            
CAPP_7343-220UF,4V,20%,POSCAP,A 724613-067               C6L8            

----------------

CAPP_7343HLF-330UF,10V,20%,POSA 724613-043               C9B8            

----------------

CAPP_7343LF-330UF,6.3V,20%,POSA 724613-042               C3B3            
CAPP_7343LF-330UF,6.3V,20%,POSA 724613-042               C4F7            
CAPP_7343LF-330UF,6.3V,20%,POSA 724613-042               C6B7            
CAPP_7343LF-330UF,6.3V,20%,POSA 724613-042               C6F4            

----------------

CAPP_SM-470UF,2V,20%,ALUM,6990A 699013-031               C2L25           
CAPP_SM-470UF,2V,20%,ALUM,6990A 699013-031               C2L46           
CAPP_SM-470UF,2V,20%,ALUM,6990A 699013-031               C3L18           
CAPP_SM-470UF,2V,20%,ALUM,6990A 699013-031               C3L19           
CAPP_SM-470UF,2V,20%,ALUM,6990A 699013-031               C3L20           
CAPP_SM-470UF,2V,20%,ALUM,6990A 699013-031               C3L21           
CAPP_SM-470UF,2V,20%,ALUM,6990A 699013-031               C7A27           
CAPP_SM-470UF,2V,20%,ALUM,6990A 699013-031               C8A15           

----------------

CAPTIVE_SCREW_TH-HDW,H57868-001 H57868-001               RM1G1           

----------------

CAP_0402-0.027UF,16V,10%,X7R,AA A36096-129               C4B6            
CAP_0402-0.027UF,16V,10%,X7R,AA A36096-129               C4G8            
CAP_0402-0.027UF,16V,10%,X7R,AA A36096-129               C7B11           
CAP_0402-0.027UF,16V,10%,X7R,AA A36096-129               C7F10           

----------------

CAP_0402-0.047UF,25V,10%,X7R,AA A36096-090               C3P45           

----------------

CAP_0402-0.220UF,16V,10%,X7R,AA A36096-104               C1A8            
CAP_0402-0.220UF,16V,10%,X7R,AA A36096-104               C1A18           
CAP_0402-0.220UF,16V,10%,X7R,AA A36096-104               C1C12           
CAP_0402-0.220UF,16V,10%,X7R,AA A36096-104               C1C24           
CAP_0402-0.220UF,16V,10%,X7R,AA A36096-104               C1D10           
CAP_0402-0.220UF,16V,10%,X7R,AA A36096-104               C1D20           
CAP_0402-0.220UF,16V,10%,X7R,AA A36096-104               C1D36           
CAP_0402-0.220UF,16V,10%,X7R,AA A36096-104               C1E11           
CAP_0402-0.220UF,16V,10%,X7R,AA A36096-104               C1F26           
CAP_0402-0.220UF,16V,10%,X7R,AA A36096-104               C1G11           
CAP_0402-0.220UF,16V,10%,X7R,AA A36096-104               C4C8            
CAP_0402-0.220UF,16V,10%,X7R,AA A36096-104               C4C17           
CAP_0402-0.220UF,16V,10%,X7R,AA A36096-104               C4D9            
CAP_0402-0.220UF,16V,10%,X7R,AA A36096-104               C4D28           
CAP_0402-0.220UF,16V,10%,X7R,AA A36096-104               C4D50           
CAP_0402-0.220UF,16V,10%,X7R,AA A36096-104               C4E17           
CAP_0402-0.220UF,16V,10%,X7R,AA A36096-104               C4E18           
CAP_0402-0.220UF,16V,10%,X7R,AA A36096-104               C7A12           
CAP_0402-0.220UF,16V,10%,X7R,AA A36096-104               C7A22           
CAP_0402-0.220UF,16V,10%,X7R,AA A36096-104               C7A43           
CAP_0402-0.220UF,16V,10%,X7R,AA A36096-104               C7A44           
CAP_0402-0.220UF,16V,10%,X7R,AA A36096-104               C7C14           
CAP_0402-0.220UF,16V,10%,X7R,AA A36096-104               C7G31           
CAP_0402-0.220UF,16V,10%,X7R,AA A36096-104               C7G38           

----------------

CAP_0402-0.22UF,16V,10%,EMPTY,A A36096-155               C3P10           
CAP_0402-0.22UF,16V,10%,EMPTY,A A36096-155               C3P12           
CAP_0402-0.22UF,16V,10%,EMPTY,A A36096-155               C3P14           
CAP_0402-0.22UF,16V,10%,EMPTY,A A36096-155               C3P16           
CAP_0402-0.22UF,16V,10%,EMPTY,A A36096-155               C3P19           
CAP_0402-0.22UF,16V,10%,EMPTY,A A36096-155               C3P21           
CAP_0402-0.22UF,16V,10%,EMPTY,A A36096-155               C3P22           
CAP_0402-0.22UF,16V,10%,EMPTY,A A36096-155               C3P24           
CAP_0402-0.22UF,16V,10%,EMPTY,A A36096-155               C3P26           
CAP_0402-0.22UF,16V,10%,EMPTY,A A36096-155               C3P29           
CAP_0402-0.22UF,16V,10%,EMPTY,A A36096-155               C3P31           
CAP_0402-0.22UF,16V,10%,EMPTY,A A36096-155               C3P33           
CAP_0402-0.22UF,16V,10%,EMPTY,A A36096-155               C3P34           
CAP_0402-0.22UF,16V,10%,EMPTY,A A36096-155               C3P36           
CAP_0402-0.22UF,16V,10%,EMPTY,A A36096-155               C3P38           
CAP_0402-0.22UF,16V,10%,EMPTY,A A36096-155               C3P41           

----------------

CAP_0402-0.22UF,16V,10%,X7R,A3A A36096-155               C1A13           
CAP_0402-0.22UF,16V,10%,X7R,A3A A36096-155               C1B21           
CAP_0402-0.22UF,16V,10%,X7R,A3A A36096-155               C1C4            
CAP_0402-0.22UF,16V,10%,X7R,A3A A36096-155               C1D6            
CAP_0402-0.22UF,16V,10%,X7R,A3A A36096-155               C1D16           
CAP_0402-0.22UF,16V,10%,X7R,A3A A36096-155               C1D33           
CAP_0402-0.22UF,16V,10%,X7R,A3A A36096-155               C1E7            
CAP_0402-0.22UF,16V,10%,X7R,A3A A36096-155               C1E25           
CAP_0402-0.22UF,16V,10%,X7R,A3A A36096-155               C1F2            
CAP_0402-0.22UF,16V,10%,X7R,A3A A36096-155               C1F3            
CAP_0402-0.22UF,16V,10%,X7R,A3A A36096-155               C1F4            
CAP_0402-0.22UF,16V,10%,X7R,A3A A36096-155               C1F5            
CAP_0402-0.22UF,16V,10%,X7R,A3A A36096-155               C1F6            
CAP_0402-0.22UF,16V,10%,X7R,A3A A36096-155               C1F8            
CAP_0402-0.22UF,16V,10%,X7R,A3A A36096-155               C1F10           
CAP_0402-0.22UF,16V,10%,X7R,A3A A36096-155               C1F11           
CAP_0402-0.22UF,16V,10%,X7R,A3A A36096-155               C1F12           
CAP_0402-0.22UF,16V,10%,X7R,A3A A36096-155               C1F13           
CAP_0402-0.22UF,16V,10%,X7R,A3A A36096-155               C1F14           
CAP_0402-0.22UF,16V,10%,X7R,A3A A36096-155               C1F15           
CAP_0402-0.22UF,16V,10%,X7R,A3A A36096-155               C1F16           
CAP_0402-0.22UF,16V,10%,X7R,A3A A36096-155               C1F17           
CAP_0402-0.22UF,16V,10%,X7R,A3A A36096-155               C1F18           
CAP_0402-0.22UF,16V,10%,X7R,A3A A36096-155               C1F20           
CAP_0402-0.22UF,16V,10%,X7R,A3A A36096-155               C1G5            
CAP_0402-0.22UF,16V,10%,X7R,A3A A36096-155               C1G29           
CAP_0402-0.22UF,16V,10%,X7R,A3A A36096-155               C1M6            
CAP_0402-0.22UF,16V,10%,X7R,A3A A36096-155               C1M7            
CAP_0402-0.22UF,16V,10%,X7R,A3A A36096-155               C1M8            
CAP_0402-0.22UF,16V,10%,X7R,A3A A36096-155               C1M9            
CAP_0402-0.22UF,16V,10%,X7R,A3A A36096-155               C1M10           
CAP_0402-0.22UF,16V,10%,X7R,A3A A36096-155               C1M11           
CAP_0402-0.22UF,16V,10%,X7R,A3A A36096-155               C1M12           
CAP_0402-0.22UF,16V,10%,X7R,A3A A36096-155               C1M13           
CAP_0402-0.22UF,16V,10%,X7R,A3A A36096-155               C1M14           
CAP_0402-0.22UF,16V,10%,X7R,A3A A36096-155               C1M15           
CAP_0402-0.22UF,16V,10%,X7R,A3A A36096-155               C1M16           
CAP_0402-0.22UF,16V,10%,X7R,A3A A36096-155               C1M17           
CAP_0402-0.22UF,16V,10%,X7R,A3A A36096-155               C1M18           
CAP_0402-0.22UF,16V,10%,X7R,A3A A36096-155               C1M19           
CAP_0402-0.22UF,16V,10%,X7R,A3A A36096-155               C1R1            
CAP_0402-0.22UF,16V,10%,X7R,A3A A36096-155               C1R2            
CAP_0402-0.22UF,16V,10%,X7R,A3A A36096-155               C1R3            
CAP_0402-0.22UF,16V,10%,X7R,A3A A36096-155               C1R4            
CAP_0402-0.22UF,16V,10%,X7R,A3A A36096-155               C1R5            
CAP_0402-0.22UF,16V,10%,X7R,A3A A36096-155               C1R6            
CAP_0402-0.22UF,16V,10%,X7R,A3A A36096-155               C1R7            
CAP_0402-0.22UF,16V,10%,X7R,A3A A36096-155               C1R8            
CAP_0402-0.22UF,16V,10%,X7R,A3A A36096-155               C1R9            
CAP_0402-0.22UF,16V,10%,X7R,A3A A36096-155               C1R10           
CAP_0402-0.22UF,16V,10%,X7R,A3A A36096-155               C2M14           
CAP_0402-0.22UF,16V,10%,X7R,A3A A36096-155               C2M15           
CAP_0402-0.22UF,16V,10%,X7R,A3A A36096-155               C2R7            
CAP_0402-0.22UF,16V,10%,X7R,A3A A36096-155               C2R8            
CAP_0402-0.22UF,16V,10%,X7R,A3A A36096-155               C2R9            
CAP_0402-0.22UF,16V,10%,X7R,A3A A36096-155               C2R10           
CAP_0402-0.22UF,16V,10%,X7R,A3A A36096-155               C2R13           
CAP_0402-0.22UF,16V,10%,X7R,A3A A36096-155               C2R14           
CAP_0402-0.22UF,16V,10%,X7R,A3A A36096-155               C2T10           
CAP_0402-0.22UF,16V,10%,X7R,A3A A36096-155               C2T11           
CAP_0402-0.22UF,16V,10%,X7R,A3A A36096-155               C2T13           
CAP_0402-0.22UF,16V,10%,X7R,A3A A36096-155               C2T14           
CAP_0402-0.22UF,16V,10%,X7R,A3A A36096-155               C2T20           
CAP_0402-0.22UF,16V,10%,X7R,A3A A36096-155               C2T23           
CAP_0402-0.22UF,16V,10%,X7R,A3A A36096-155               C2U3            
CAP_0402-0.22UF,16V,10%,X7R,A3A A36096-155               C2U4            
CAP_0402-0.22UF,16V,10%,X7R,A3A A36096-155               C2U5            
CAP_0402-0.22UF,16V,10%,X7R,A3A A36096-155               C2U6            
CAP_0402-0.22UF,16V,10%,X7R,A3A A36096-155               C2U7            
CAP_0402-0.22UF,16V,10%,X7R,A3A A36096-155               C2U8            
CAP_0402-0.22UF,16V,10%,X7R,A3A A36096-155               C2U9            
CAP_0402-0.22UF,16V,10%,X7R,A3A A36096-155               C2U10           
CAP_0402-0.22UF,16V,10%,X7R,A3A A36096-155               C2U11           
CAP_0402-0.22UF,16V,10%,X7R,A3A A36096-155               C2U12           
CAP_0402-0.22UF,16V,10%,X7R,A3A A36096-155               C2U13           
CAP_0402-0.22UF,16V,10%,X7R,A3A A36096-155               C2U14           
CAP_0402-0.22UF,16V,10%,X7R,A3A A36096-155               C2U15           
CAP_0402-0.22UF,16V,10%,X7R,A3A A36096-155               C2U16           
CAP_0402-0.22UF,16V,10%,X7R,A3A A36096-155               C2U17           
CAP_0402-0.22UF,16V,10%,X7R,A3A A36096-155               C2U18           
CAP_0402-0.22UF,16V,10%,X7R,A3A A36096-155               C3M1            
CAP_0402-0.22UF,16V,10%,X7R,A3A A36096-155               C3M2            
CAP_0402-0.22UF,16V,10%,X7R,A3A A36096-155               C3M3            
CAP_0402-0.22UF,16V,10%,X7R,A3A A36096-155               C3M4            
CAP_0402-0.22UF,16V,10%,X7R,A3A A36096-155               C3M11           
CAP_0402-0.22UF,16V,10%,X7R,A3A A36096-155               C3M12           
CAP_0402-0.22UF,16V,10%,X7R,A3A A36096-155               C3M13           
CAP_0402-0.22UF,16V,10%,X7R,A3A A36096-155               C3M14           
CAP_0402-0.22UF,16V,10%,X7R,A3A A36096-155               C3M25           
CAP_0402-0.22UF,16V,10%,X7R,A3A A36096-155               C3M26           
CAP_0402-0.22UF,16V,10%,X7R,A3A A36096-155               C3M28           
CAP_0402-0.22UF,16V,10%,X7R,A3A A36096-155               C3M32           
CAP_0402-0.22UF,16V,10%,X7R,A3A A36096-155               C3M33           
CAP_0402-0.22UF,16V,10%,X7R,A3A A36096-155               C3M34           
CAP_0402-0.22UF,16V,10%,X7R,A3A A36096-155               C3M35           
CAP_0402-0.22UF,16V,10%,X7R,A3A A36096-155               C3M36           
CAP_0402-0.22UF,16V,10%,X7R,A3A A36096-155               C3M37           
CAP_0402-0.22UF,16V,10%,X7R,A3A A36096-155               C3M40           
CAP_0402-0.22UF,16V,10%,X7R,A3A A36096-155               C3M41           
CAP_0402-0.22UF,16V,10%,X7R,A3A A36096-155               C3M44           
CAP_0402-0.22UF,16V,10%,X7R,A3A A36096-155               C3M45           
CAP_0402-0.22UF,16V,10%,X7R,A3A A36096-155               C3N8            
CAP_0402-0.22UF,16V,10%,X7R,A3A A36096-155               C3N9            
CAP_0402-0.22UF,16V,10%,X7R,A3A A36096-155               C3N13           
CAP_0402-0.22UF,16V,10%,X7R,A3A A36096-155               C3P11           
CAP_0402-0.22UF,16V,10%,X7R,A3A A36096-155               C3P13           
CAP_0402-0.22UF,16V,10%,X7R,A3A A36096-155               C3P15           
CAP_0402-0.22UF,16V,10%,X7R,A3A A36096-155               C3P17           
CAP_0402-0.22UF,16V,10%,X7R,A3A A36096-155               C3P18           
CAP_0402-0.22UF,16V,10%,X7R,A3A A36096-155               C3P20           
CAP_0402-0.22UF,16V,10%,X7R,A3A A36096-155               C3P23           
CAP_0402-0.22UF,16V,10%,X7R,A3A A36096-155               C3P25           
CAP_0402-0.22UF,16V,10%,X7R,A3A A36096-155               C3P27           
CAP_0402-0.22UF,16V,10%,X7R,A3A A36096-155               C3P28           
CAP_0402-0.22UF,16V,10%,X7R,A3A A36096-155               C3P30           
CAP_0402-0.22UF,16V,10%,X7R,A3A A36096-155               C3P32           
CAP_0402-0.22UF,16V,10%,X7R,A3A A36096-155               C3P35           
CAP_0402-0.22UF,16V,10%,X7R,A3A A36096-155               C3P37           
CAP_0402-0.22UF,16V,10%,X7R,A3A A36096-155               C3P39           
CAP_0402-0.22UF,16V,10%,X7R,A3A A36096-155               C3P40           
CAP_0402-0.22UF,16V,10%,X7R,A3A A36096-155               C4C5            
CAP_0402-0.22UF,16V,10%,X7R,A3A A36096-155               C4D5            
CAP_0402-0.22UF,16V,10%,X7R,A3A A36096-155               C4D13           
CAP_0402-0.22UF,16V,10%,X7R,A3A A36096-155               C4D47           
CAP_0402-0.22UF,16V,10%,X7R,A3A A36096-155               C4E5            
CAP_0402-0.22UF,16V,10%,X7R,A3A A36096-155               C4E23           
CAP_0402-0.22UF,16V,10%,X7R,A3A A36096-155               C4E27           
CAP_0402-0.22UF,16V,10%,X7R,A3A A36096-155               C6B4            
CAP_0402-0.22UF,16V,10%,X7R,A3A A36096-155               C6B5            
CAP_0402-0.22UF,16V,10%,X7R,A3A A36096-155               C6B6            
CAP_0402-0.22UF,16V,10%,X7R,A3A A36096-155               C6B8            
CAP_0402-0.22UF,16V,10%,X7R,A3A A36096-155               C6B9            
CAP_0402-0.22UF,16V,10%,X7R,A3A A36096-155               C6B10           
CAP_0402-0.22UF,16V,10%,X7R,A3A A36096-155               C6B11           
CAP_0402-0.22UF,16V,10%,X7R,A3A A36096-155               C6B12           
CAP_0402-0.22UF,16V,10%,X7R,A3A A36096-155               C6B13           
CAP_0402-0.22UF,16V,10%,X7R,A3A A36096-155               C6B14           
CAP_0402-0.22UF,16V,10%,X7R,A3A A36096-155               C6B15           
CAP_0402-0.22UF,16V,10%,X7R,A3A A36096-155               C6B16           
CAP_0402-0.22UF,16V,10%,X7R,A3A A36096-155               C6B17           
CAP_0402-0.22UF,16V,10%,X7R,A3A A36096-155               C6B18           
CAP_0402-0.22UF,16V,10%,X7R,A3A A36096-155               C6B19           
CAP_0402-0.22UF,16V,10%,X7R,A3A A36096-155               C6B20           
CAP_0402-0.22UF,16V,10%,X7R,A3A A36096-155               C7A8            
CAP_0402-0.22UF,16V,10%,X7R,A3A A36096-155               C7A17           
CAP_0402-0.22UF,16V,10%,X7R,A3A A36096-155               C7A25           
CAP_0402-0.22UF,16V,10%,X7R,A3A A36096-155               C7A41           
CAP_0402-0.22UF,16V,10%,X7R,A3A A36096-155               C7B25           
CAP_0402-0.22UF,16V,10%,X7R,A3A A36096-155               C7B26           
CAP_0402-0.22UF,16V,10%,X7R,A3A A36096-155               C7B27           
CAP_0402-0.22UF,16V,10%,X7R,A3A A36096-155               C7B28           
CAP_0402-0.22UF,16V,10%,X7R,A3A A36096-155               C7B29           
CAP_0402-0.22UF,16V,10%,X7R,A3A A36096-155               C7C1            
CAP_0402-0.22UF,16V,10%,X7R,A3A A36096-155               C7C2            
CAP_0402-0.22UF,16V,10%,X7R,A3A A36096-155               C7C3            
CAP_0402-0.22UF,16V,10%,X7R,A3A A36096-155               C7C18           
CAP_0402-0.22UF,16V,10%,X7R,A3A A36096-155               C7G5            
CAP_0402-0.22UF,16V,10%,X7R,A3A A36096-155               C7G6            
CAP_0402-0.22UF,16V,10%,X7R,A3A A36096-155               C7G7            
CAP_0402-0.22UF,16V,10%,X7R,A3A A36096-155               C7G8            
CAP_0402-0.22UF,16V,10%,X7R,A3A A36096-155               C7G9            
CAP_0402-0.22UF,16V,10%,X7R,A3A A36096-155               C7G10           
CAP_0402-0.22UF,16V,10%,X7R,A3A A36096-155               C7G11           
CAP_0402-0.22UF,16V,10%,X7R,A3A A36096-155               C7G12           
CAP_0402-0.22UF,16V,10%,X7R,A3A A36096-155               C7G13           
CAP_0402-0.22UF,16V,10%,X7R,A3A A36096-155               C7G14           
CAP_0402-0.22UF,16V,10%,X7R,A3A A36096-155               C7G15           
CAP_0402-0.22UF,16V,10%,X7R,A3A A36096-155               C7G16           
CAP_0402-0.22UF,16V,10%,X7R,A3A A36096-155               C7G17           
CAP_0402-0.22UF,16V,10%,X7R,A3A A36096-155               C7G18           
CAP_0402-0.22UF,16V,10%,X7R,A3A A36096-155               C7G19           
CAP_0402-0.22UF,16V,10%,X7R,A3A A36096-155               C7G20           
CAP_0402-0.22UF,16V,10%,X7R,A3A A36096-155               C7G21           
CAP_0402-0.22UF,16V,10%,X7R,A3A A36096-155               C7G22           
CAP_0402-0.22UF,16V,10%,X7R,A3A A36096-155               C7G23           
CAP_0402-0.22UF,16V,10%,X7R,A3A A36096-155               C7G24           
CAP_0402-0.22UF,16V,10%,X7R,A3A A36096-155               C7G25           
CAP_0402-0.22UF,16V,10%,X7R,A3A A36096-155               C7G26           
CAP_0402-0.22UF,16V,10%,X7R,A3A A36096-155               C7G34           
CAP_0402-0.22UF,16V,10%,X7R,A3A A36096-155               C7G41           
CAP_0402-0.22UF,16V,10%,X7R,A3A A36096-155               C8F7            
CAP_0402-0.22UF,16V,10%,X7R,A3A A36096-155               C8F12           
CAP_0402-0.22UF,16V,10%,X7R,A3A A36096-155               C8G1            
CAP_0402-0.22UF,16V,10%,X7R,A3A A36096-155               C8G2            
CAP_0402-0.22UF,16V,10%,X7R,A3A A36096-155               C8G3            
CAP_0402-0.22UF,16V,10%,X7R,A3A A36096-155               C8G4            
CAP_0402-0.22UF,16V,10%,X7R,A3A A36096-155               C8G5            
CAP_0402-0.22UF,16V,10%,X7R,A3A A36096-155               C8G6            
CAP_0402-0.22UF,16V,10%,X7R,A3A A36096-155               C8G7            
CAP_0402-0.22UF,16V,10%,X7R,A3A A36096-155               C8G8            
CAP_0402-0.22UF,16V,10%,X7R,A3A A36096-155               C8G9            
CAP_0402-0.22UF,16V,10%,X7R,A3A A36096-155               C8G10           
CAP_0402-0.22UF,16V,10%,X7R,A3A A36096-155               C9N1            
CAP_0402-0.22UF,16V,10%,X7R,A3A A36096-155               C9N2            
CAP_0402-0.22UF,16V,10%,X7R,A3A A36096-155               C9N3            
CAP_0402-0.22UF,16V,10%,X7R,A3A A36096-155               C9N4            
CAP_0402-0.22UF,16V,10%,X7R,A3A A36096-155               C9N5            
CAP_0402-0.22UF,16V,10%,X7R,A3A A36096-155               C9N6            
CAP_0402-0.22UF,16V,10%,X7R,A3A A36096-155               C9N7            
CAP_0402-0.22UF,16V,10%,X7R,A3A A36096-155               C9N8            
CAP_0402-0.22UF,16V,10%,X7R,A3A A36096-155               C9N9            
CAP_0402-0.22UF,16V,10%,X7R,A3A A36096-155               C9N10           
CAP_0402-0.22UF,16V,10%,X7R,A3A A36096-155               C9N12           
CAP_0402-0.22UF,16V,10%,X7R,A3A A36096-155               C9N14           
CAP_0402-0.22UF,16V,10%,X7R,A3A A36096-155               C9N15           
CAP_0402-0.22UF,16V,10%,X7R,A3A A36096-155               C9N16           
CAP_0402-0.22UF,16V,10%,X7R,A3A A36096-155               C9N17           
CAP_0402-0.22UF,16V,10%,X7R,A3A A36096-155               C9N18           

----------------

CAP_0402-1.0UF,16V,10%,X6S,D97A D97712-011               C1A6            
CAP_0402-1.0UF,16V,10%,X6S,D97A D97712-011               C1A9            
CAP_0402-1.0UF,16V,10%,X6S,D97A D97712-011               C1A19           
CAP_0402-1.0UF,16V,10%,X6S,D97A D97712-011               C1B20           
CAP_0402-1.0UF,16V,10%,X6S,D97A D97712-011               C1C5            
CAP_0402-1.0UF,16V,10%,X6S,D97A D97712-011               C1C15           
CAP_0402-1.0UF,16V,10%,X6S,D97A D97712-011               C1C26           
CAP_0402-1.0UF,16V,10%,X6S,D97A D97712-011               C1D7            
CAP_0402-1.0UF,16V,10%,X6S,D97A D97712-011               C1D12           
CAP_0402-1.0UF,16V,10%,X6S,D97A D97712-011               C1D17           
CAP_0402-1.0UF,16V,10%,X6S,D97A D97712-011               C1D19           
CAP_0402-1.0UF,16V,10%,X6S,D97A D97712-011               C1D23           
CAP_0402-1.0UF,16V,10%,X6S,D97A D97712-011               C1D25           
CAP_0402-1.0UF,16V,10%,X6S,D97A D97712-011               C1D32           
CAP_0402-1.0UF,16V,10%,X6S,D97A D97712-011               C1D35           
CAP_0402-1.0UF,16V,10%,X6S,D97A D97712-011               C1E8            
CAP_0402-1.0UF,16V,10%,X6S,D97A D97712-011               C1E13           
CAP_0402-1.0UF,16V,10%,X6S,D97A D97712-011               C1E24           
CAP_0402-1.0UF,16V,10%,X6S,D97A D97712-011               C1F27           
CAP_0402-1.0UF,16V,10%,X6S,D97A D97712-011               C1G6            
CAP_0402-1.0UF,16V,10%,X6S,D97A D97712-011               C1G13           
CAP_0402-1.0UF,16V,10%,X6S,D97A D97712-011               C1G28           
CAP_0402-1.0UF,16V,10%,X6S,D97A D97712-011               C1L1            
CAP_0402-1.0UF,16V,10%,X6S,D97A D97712-011               C1L19           
CAP_0402-1.0UF,16V,10%,X6S,D97A D97712-011               C1U19           
CAP_0402-1.0UF,16V,10%,X6S,D97A D97712-011               C3M9            
CAP_0402-1.0UF,16V,10%,X6S,D97A D97712-011               C3P50           
CAP_0402-1.0UF,16V,10%,X6S,D97A D97712-011               C3T10           
CAP_0402-1.0UF,16V,10%,X6S,D97A D97712-011               C4A8            
CAP_0402-1.0UF,16V,10%,X6S,D97A D97712-011               C4A9            
CAP_0402-1.0UF,16V,10%,X6S,D97A D97712-011               C4A10           
CAP_0402-1.0UF,16V,10%,X6S,D97A D97712-011               C4A14           
CAP_0402-1.0UF,16V,10%,X6S,D97A D97712-011               C4C6            
CAP_0402-1.0UF,16V,10%,X6S,D97A D97712-011               C4C9            
CAP_0402-1.0UF,16V,10%,X6S,D97A D97712-011               C4C18           
CAP_0402-1.0UF,16V,10%,X6S,D97A D97712-011               C4D7            
CAP_0402-1.0UF,16V,10%,X6S,D97A D97712-011               C4D10           
CAP_0402-1.0UF,16V,10%,X6S,D97A D97712-011               C4D16           
CAP_0402-1.0UF,16V,10%,X6S,D97A D97712-011               C4D30           
CAP_0402-1.0UF,16V,10%,X6S,D97A D97712-011               C4D46           
CAP_0402-1.0UF,16V,10%,X6S,D97A D97712-011               C4D48           
CAP_0402-1.0UF,16V,10%,X6S,D97A D97712-011               C4E10           
CAP_0402-1.0UF,16V,10%,X6S,D97A D97712-011               C4E15           
CAP_0402-1.0UF,16V,10%,X6S,D97A D97712-011               C4E19           
CAP_0402-1.0UF,16V,10%,X6S,D97A D97712-011               C4E22           
CAP_0402-1.0UF,16V,10%,X6S,D97A D97712-011               C4E26           
CAP_0402-1.0UF,16V,10%,X6S,D97A D97712-011               C4G4            
CAP_0402-1.0UF,16V,10%,X6S,D97A D97712-011               C4G15           
CAP_0402-1.0UF,16V,10%,X6S,D97A D97712-011               C4G16           
CAP_0402-1.0UF,16V,10%,X6S,D97A D97712-011               C4G18           
CAP_0402-1.0UF,16V,10%,X6S,D97A D97712-011               C4G21           
CAP_0402-1.0UF,16V,10%,X6S,D97A D97712-011               C6L11           
CAP_0402-1.0UF,16V,10%,X6S,D97A D97712-011               C7A6            
CAP_0402-1.0UF,16V,10%,X6S,D97A D97712-011               C7A7            
CAP_0402-1.0UF,16V,10%,X6S,D97A D97712-011               C7A9            
CAP_0402-1.0UF,16V,10%,X6S,D97A D97712-011               C7A10           
CAP_0402-1.0UF,16V,10%,X6S,D97A D97712-011               C7A11           
CAP_0402-1.0UF,16V,10%,X6S,D97A D97712-011               C7A16           
CAP_0402-1.0UF,16V,10%,X6S,D97A D97712-011               C7A21           
CAP_0402-1.0UF,16V,10%,X6S,D97A D97712-011               C7A24           
CAP_0402-1.0UF,16V,10%,X6S,D97A D97712-011               C7C12           
CAP_0402-1.0UF,16V,10%,X6S,D97A D97712-011               C7C17           
CAP_0402-1.0UF,16V,10%,X6S,D97A D97712-011               C7D4            
CAP_0402-1.0UF,16V,10%,X6S,D97A D97712-011               C7E14           
CAP_0402-1.0UF,16V,10%,X6S,D97A D97712-011               C7G30           
CAP_0402-1.0UF,16V,10%,X6S,D97A D97712-011               C7G33           
CAP_0402-1.0UF,16V,10%,X6S,D97A D97712-011               C7G37           
CAP_0402-1.0UF,16V,10%,X6S,D97A D97712-011               C7G40           
CAP_0402-1.0UF,16V,10%,X6S,D97A D97712-011               C8E14           
CAP_0402-1.0UF,16V,10%,X6S,D97A D97712-011               C9E11           

----------------

CAP_0402-1.0UF,16V,10%,X7S,G71A G71842-007               C9G5            

----------------

CAP_0402LF-0.022UF,16V,10%,X7RA A36096-073               C8E15           

----------------

CAP_0402LF-0.039UF,25V,10%,X7RA A36096-063               C9E7            

----------------

CAP_0402LF-10.0PF,50V,5%,COG,AA A36094-025               C9G22           

----------------

CAP_0402LF-100.0PF,50V,5%,COG,A A36095-026               C1T20           
CAP_0402LF-100.0PF,50V,5%,COG,A A36095-026               C1U2            
CAP_0402LF-100.0PF,50V,5%,COG,A A36095-026               C1U17           
CAP_0402LF-100.0PF,50V,5%,COG,A A36095-026               C4B4            
CAP_0402LF-100.0PF,50V,5%,COG,A A36095-026               C4G6            
CAP_0402LF-100.0PF,50V,5%,COG,A A36095-026               C7B10           
CAP_0402LF-100.0PF,50V,5%,COG,A A36095-026               C7F9            
CAP_0402LF-100.0PF,50V,5%,COG,A A36095-026               C9F18           

----------------

CAP_0402LF-1000PF,50V,10%,EMPTA A36096-046               C4A2            
CAP_0402LF-1000PF,50V,10%,EMPTA A36096-046               C4A6            
CAP_0402LF-1000PF,50V,10%,EMPTA A36096-046               C4B5            
CAP_0402LF-1000PF,50V,10%,EMPTA A36096-046               C4G7            
CAP_0402LF-1000PF,50V,10%,EMPTA A36096-046               C4G12           
CAP_0402LF-1000PF,50V,10%,EMPTA A36096-046               C4G23           
CAP_0402LF-1000PF,50V,10%,EMPTA A36096-046               C7B9            
CAP_0402LF-1000PF,50V,10%,EMPTA A36096-046               C7F8            
CAP_0402LF-1000PF,50V,10%,EMPTA A36096-046               C8A10           
CAP_0402LF-1000PF,50V,10%,EMPTA A36096-046               C8E13           
CAP_0402LF-1000PF,50V,10%,EMPTA A36096-046               C8E17           
CAP_0402LF-1000PF,50V,10%,EMPTA A36096-046               C9F6            
CAP_0402LF-1000PF,50V,10%,EMPTA A36096-046               C9F9            

----------------

CAP_0402LF-1000PF,50V,10%,X7R,A A36096-046               C1B4            
CAP_0402LF-1000PF,50V,10%,X7R,A A36096-046               C1B8            
CAP_0402LF-1000PF,50V,10%,X7R,A A36096-046               C1C8            
CAP_0402LF-1000PF,50V,10%,X7R,A A36096-046               C1C23           
CAP_0402LF-1000PF,50V,10%,X7R,A A36096-046               C1G21           
CAP_0402LF-1000PF,50V,10%,X7R,A A36096-046               C1G26           
CAP_0402LF-1000PF,50V,10%,X7R,A A36096-046               C3P2            
CAP_0402LF-1000PF,50V,10%,X7R,A A36096-046               C3P6            
CAP_0402LF-1000PF,50V,10%,X7R,A A36096-046               C4A3            
CAP_0402LF-1000PF,50V,10%,X7R,A A36096-046               C4A12           
CAP_0402LF-1000PF,50V,10%,X7R,A A36096-046               C4B8            
CAP_0402LF-1000PF,50V,10%,X7R,A A36096-046               C4D20           
CAP_0402LF-1000PF,50V,10%,X7R,A A36096-046               C4D33           
CAP_0402LF-1000PF,50V,10%,X7R,A A36096-046               C4D40           
CAP_0402LF-1000PF,50V,10%,X7R,A A36096-046               C4D42           
CAP_0402LF-1000PF,50V,10%,X7R,A A36096-046               C4G9            
CAP_0402LF-1000PF,50V,10%,X7R,A A36096-046               C4G13           
CAP_0402LF-1000PF,50V,10%,X7R,A A36096-046               C4G14           
CAP_0402LF-1000PF,50V,10%,X7R,A A36096-046               C7A35           
CAP_0402LF-1000PF,50V,10%,X7R,A A36096-046               C7B3            
CAP_0402LF-1000PF,50V,10%,X7R,A A36096-046               C7B12           
CAP_0402LF-1000PF,50V,10%,X7R,A A36096-046               C7E10           
CAP_0402LF-1000PF,50V,10%,X7R,A A36096-046               C7F11           
CAP_0402LF-1000PF,50V,10%,X7R,A A36096-046               C7F14           
CAP_0402LF-1000PF,50V,10%,X7R,A A36096-046               C7G1            
CAP_0402LF-1000PF,50V,10%,X7R,A A36096-046               C8A3            
CAP_0402LF-1000PF,50V,10%,X7R,A A36096-046               C8A9            
CAP_0402LF-1000PF,50V,10%,X7R,A A36096-046               C8A11           
CAP_0402LF-1000PF,50V,10%,X7R,A A36096-046               C8F2            
CAP_0402LF-1000PF,50V,10%,X7R,A A36096-046               C9F8            
CAP_0402LF-1000PF,50V,10%,X7R,A A36096-046               C9F10           
CAP_0402LF-1000PF,50V,10%,X7R,A A36096-046               CTI2            
CAP_0402LF-1000PF,50V,10%,X7R,A A36096-046               CTI4            
CAP_0402LF-1000PF,50V,10%,X7R,A A36096-046               CTI8            
CAP_0402LF-1000PF,50V,10%,X7R,A A36096-046               CTI10           
CAP_0402LF-1000PF,50V,10%,X7R,A A36096-046               CTI15           
CAP_0402LF-1000PF,50V,10%,X7R,A A36096-046               CTI17           
CAP_0402LF-1000PF,50V,10%,X7R,A A36096-046               CTI19           
CAP_0402LF-1000PF,50V,10%,X7R,A A36096-046               CTI22           
CAP_0402LF-1000PF,50V,10%,X7R,A A36096-046               CTI26           
CAP_0402LF-1000PF,50V,10%,X7R,A A36096-046               CTI28           
CAP_0402LF-1000PF,50V,10%,X7R,A A36096-046               CTI32           
CAP_0402LF-1000PF,50V,10%,X7R,A A36096-046               CTI34           
CAP_0402LF-1000PF,50V,10%,X7R,A A36096-046               CTI37           
CAP_0402LF-1000PF,50V,10%,X7R,A A36096-046               CTI42           
CAP_0402LF-1000PF,50V,10%,X7R,A A36096-046               CTI43           
CAP_0402LF-1000PF,50V,10%,X7R,A A36096-046               CTI48           
CAP_0402LF-1000PF,50V,10%,X7R,A A36096-046               CTI49           
CAP_0402LF-1000PF,50V,10%,X7R,A A36096-046               CTI54           
CAP_0402LF-1000PF,50V,10%,X7R,A A36096-046               CTI55           
CAP_0402LF-1000PF,50V,10%,X7R,A A36096-046               CTI58           
CAP_0402LF-1000PF,50V,10%,X7R,A A36096-046               CTI61           
CAP_0402LF-1000PF,50V,10%,X7R,A A36096-046               CTI64           
CAP_0402LF-1000PF,50V,10%,X7R,A A36096-046               CTI69           
CAP_0402LF-1000PF,50V,10%,X7R,A A36096-046               CTI71           

----------------

CAP_0402LF-12.0PF,50V,5%,COG,AA A36095-043               C9F20           
CAP_0402LF-12.0PF,50V,5%,COG,AA A36095-043               C9F21           

----------------

CAP_0402LF-15.0PF,50V,5%,COG,AA A36095-047               C7C4            
CAP_0402LF-15.0PF,50V,5%,COG,AA A36095-047               C7C5            

----------------

CAP_0402LF-18PF,50V,5%,C0G,A36A A36095-042               C7C13           
CAP_0402LF-18PF,50V,5%,C0G,A36A A36095-042               C7C15           

----------------

CAP_0402LF-22.0PF,50V,5%,COG,AA A36095-030               C9E8            
CAP_0402LF-22.0PF,50V,5%,COG,AA A36095-030               C9E9            

----------------

CAP_0402LF-2200PF,50V,10%,X7R,A A36096-075               C4B7            
CAP_0402LF-2200PF,50V,10%,X7R,A A36096-075               C4B9            
CAP_0402LF-2200PF,50V,10%,X7R,A A36096-075               C4G10           
CAP_0402LF-2200PF,50V,10%,X7R,A A36096-075               C4G11           
CAP_0402LF-2200PF,50V,10%,X7R,A A36096-075               C7B13           
CAP_0402LF-2200PF,50V,10%,X7R,A A36096-075               C7B14           
CAP_0402LF-2200PF,50V,10%,X7R,A A36096-075               C7F12           
CAP_0402LF-2200PF,50V,10%,X7R,A A36096-075               C7F13           
CAP_0402LF-2200PF,50V,10%,X7R,A A36096-075               C8F1            

----------------

CAP_0402LF-220PF,50V,10%,X7R,AA A36096-050               C1B11           
CAP_0402LF-220PF,50V,10%,X7R,AA A36096-050               C1B12           
CAP_0402LF-220PF,50V,10%,X7R,AA A36096-050               C1C10           
CAP_0402LF-220PF,50V,10%,X7R,AA A36096-050               C1C11           
CAP_0402LF-220PF,50V,10%,X7R,AA A36096-050               C1C16           
CAP_0402LF-220PF,50V,10%,X7R,AA A36096-050               C1D1            
CAP_0402LF-220PF,50V,10%,X7R,AA A36096-050               C1G16           
CAP_0402LF-220PF,50V,10%,X7R,AA A36096-050               C1G24           
CAP_0402LF-220PF,50V,10%,X7R,AA A36096-050               C2L2            
CAP_0402LF-220PF,50V,10%,X7R,AA A36096-050               C3N39           
CAP_0402LF-220PF,50V,10%,X7R,AA A36096-050               C4D17           
CAP_0402LF-220PF,50V,10%,X7R,AA A36096-050               C4D18           
CAP_0402LF-220PF,50V,10%,X7R,AA A36096-050               C4D29           
CAP_0402LF-220PF,50V,10%,X7R,AA A36096-050               C4D44           
CAP_0402LF-220PF,50V,10%,X7R,AA A36096-050               C4D45           
CAP_0402LF-220PF,50V,10%,X7R,AA A36096-050               C7A28           
CAP_0402LF-220PF,50V,10%,X7R,AA A36096-050               C7A29           
CAP_0402LF-220PF,50V,10%,X7R,AA A36096-050               C7G3            
CAP_0402LF-220PF,50V,10%,X7R,AA A36096-050               C7G4            
CAP_0402LF-220PF,50V,10%,X7R,AA A36096-050               C8A2            

----------------

CAP_0402LF-27.0PF,50V,5%,COG,AA A36095-038               C8F18           
CAP_0402LF-27.0PF,50V,5%,COG,AA A36095-038               C8F19           

----------------

CAP_0402LF-270PF,50V,10%,X7R,AA A36096-065               C8E16           

----------------

CAP_0402LF-33.0PF,50V,5%,COG,AA A36095-031               C8C1            
CAP_0402LF-33.0PF,50V,5%,COG,AA A36095-031               C8C2            

----------------

CAP_0402LF-3300PF,50V,10%,EMPTA A36096-091               C4A16           
CAP_0402LF-3300PF,50V,10%,EMPTA A36096-091               C4F12           
CAP_0402LF-3300PF,50V,10%,EMPTA A36096-091               C7A34           
CAP_0402LF-3300PF,50V,10%,EMPTA A36096-091               C7F3            
CAP_0402LF-3300PF,50V,10%,EMPTA A36096-091               C8F3            

----------------

CAP_0402LF-47.0PF,50V,5%,COG,AA A36095-025               C1U21           
CAP_0402LF-47.0PF,50V,5%,COG,AA A36095-025               C9G14           
CAP_0402LF-47.0PF,50V,5%,COG,AA A36095-025               C9G15           
CAP_0402LF-47.0PF,50V,5%,COG,AA A36095-025               C9G17           
CAP_0402LF-47.0PF,50V,5%,COG,AA A36095-025               C9G18           
CAP_0402LF-47.0PF,50V,5%,COG,AA A36095-025               C9G20           
CAP_0402LF-47.0PF,50V,5%,COG,AA A36095-025               C9G21           

----------------

CAP_0402LF-47.0PF,50V,5%,EMPTYA A36095-025               C1E19           
CAP_0402LF-47.0PF,50V,5%,EMPTYA A36095-025               C1M4            

----------------

CAP_0402LF-4700PF,50V,10%,EMPTA A36096-066               C9G9            
CAP_0402LF-4700PF,50V,10%,EMPTA A36096-066               C9G12           
CAP_0402LF-4700PF,50V,10%,EMPTA A36096-066               C9G13           
CAP_0402LF-4700PF,50V,10%,EMPTA A36096-066               C9G16           

----------------

CAP_0402LF-470PF,50V,10%,EMPTYA A36096-049               C2R6            
CAP_0402LF-470PF,50V,10%,EMPTYA A36096-049               C8D3            

----------------

CAP_0402LF-470PF,50V,10%,X7R,AA A36096-049               C9F22           
CAP_0402LF-470PF,50V,10%,X7R,AA A36096-049               C9G1            
CAP_0402LF-470PF,50V,10%,X7R,AA A36096-049               C9G2            
CAP_0402LF-470PF,50V,10%,X7R,AA A36096-049               C9G3            

----------------

CAP_0603-0.47UF,16V,10%,X7R,20A 202297-006               C1T42           

----------------

CAP_0603-10UF,6.3V,20%,EMPTY,EA E15431-002               C1T16           
CAP_0603-10UF,6.3V,20%,EMPTY,EA E15431-002               C8F10           

----------------

CAP_0603-10UF,6.3V,20%,X6S,E15A E15431-002               C1R13           
CAP_0603-10UF,6.3V,20%,X6S,E15A E15431-002               C1R16           
CAP_0603-10UF,6.3V,20%,X6S,E15A E15431-002               C1R17           
CAP_0603-10UF,6.3V,20%,X6S,E15A E15431-002               C1R22           
CAP_0603-10UF,6.3V,20%,X6S,E15A E15431-002               C1R30           
CAP_0603-10UF,6.3V,20%,X6S,E15A E15431-002               C1T4            
CAP_0603-10UF,6.3V,20%,X6S,E15A E15431-002               C1T7            
CAP_0603-10UF,6.3V,20%,X6S,E15A E15431-002               C1T15           
CAP_0603-10UF,6.3V,20%,X6S,E15A E15431-002               C2N14           
CAP_0603-10UF,6.3V,20%,X6S,E15A E15431-002               C2N17           
CAP_0603-10UF,6.3V,20%,X6S,E15A E15431-002               C2N21           
CAP_0603-10UF,6.3V,20%,X6S,E15A E15431-002               C2N22           
CAP_0603-10UF,6.3V,20%,X6S,E15A E15431-002               C2N23           
CAP_0603-10UF,6.3V,20%,X6S,E15A E15431-002               C2N24           
CAP_0603-10UF,6.3V,20%,X6S,E15A E15431-002               C7D2            
CAP_0603-10UF,6.3V,20%,X6S,E15A E15431-002               C8A6            
CAP_0603-10UF,6.3V,20%,X6S,E15A E15431-002               C8C3            
CAP_0603-10UF,6.3V,20%,X6S,E15A E15431-002               C8C4            
CAP_0603-10UF,6.3V,20%,X6S,E15A E15431-002               C8C5            
CAP_0603-10UF,6.3V,20%,X6S,E15A E15431-002               C8C6            
CAP_0603-10UF,6.3V,20%,X6S,E15A E15431-002               C9E10           
CAP_0603-10UF,6.3V,20%,X6S,E15A E15431-002               C9F3            

----------------

CAP_0603-4.7UF,6.3V,10%,X6S,E1A E15431-003               C1T44           
CAP_0603-4.7UF,6.3V,10%,X6S,E1A E15431-003               C2R11           
CAP_0603-4.7UF,6.3V,10%,X6S,E1A E15431-003               C3M10           
CAP_0603-4.7UF,6.3V,10%,X6S,E1A E15431-003               C3T11           
CAP_0603-4.7UF,6.3V,10%,X6S,E1A E15431-003               C4A7            
CAP_0603-4.7UF,6.3V,10%,X6S,E1A E15431-003               C4A11           
CAP_0603-4.7UF,6.3V,10%,X6S,E1A E15431-003               C6L12           
CAP_0603-4.7UF,6.3V,10%,X6S,E1A E15431-003               C6U6            
CAP_0603-4.7UF,6.3V,10%,X6S,E1A E15431-003               C6U11           
CAP_0603-4.7UF,6.3V,10%,X6S,E1A E15431-003               C6U12           

----------------

CAP_0603LF-0.033UF,50V,10%,X7RA 603269-064               C9P14           

----------------

CAP_0603LF-0.1UF,25V,10%,X7R,6A 602433-020               C4B15           
CAP_0603LF-0.1UF,25V,10%,X7R,6A 602433-020               C4G26           
CAP_0603LF-0.1UF,25V,10%,X7R,6A 602433-020               C7B30           
CAP_0603LF-0.1UF,25V,10%,X7R,6A 602433-020               C7F4            
CAP_0603LF-0.1UF,25V,10%,X7R,6A 602433-020               C8A4            
CAP_0603LF-0.1UF,25V,10%,X7R,6A 602433-020               C8E6            
CAP_0603LF-0.1UF,25V,10%,X7R,6A 602433-020               C8E12           

----------------

CAP_0603LF-10UF,4V,20%,X6S,E15A E15431-001               C2D4            
CAP_0603LF-10UF,4V,20%,X6S,E15A E15431-001               C2D5            
CAP_0603LF-10UF,4V,20%,X6S,E15A E15431-001               C2D6            
CAP_0603LF-10UF,4V,20%,X6S,E15A E15431-001               C2D7            
CAP_0603LF-10UF,4V,20%,X6S,E15A E15431-001               C2D8            
CAP_0603LF-10UF,4V,20%,X6S,E15A E15431-001               C2D9            
CAP_0603LF-10UF,4V,20%,X6S,E15A E15431-001               C2D10           
CAP_0603LF-10UF,4V,20%,X6S,E15A E15431-001               C2D11           
CAP_0603LF-10UF,4V,20%,X6S,E15A E15431-001               C2D41           
CAP_0603LF-10UF,4V,20%,X6S,E15A E15431-001               C2D42           
CAP_0603LF-10UF,4V,20%,X6S,E15A E15431-001               C2D43           
CAP_0603LF-10UF,4V,20%,X6S,E15A E15431-001               C2D44           
CAP_0603LF-10UF,4V,20%,X6S,E15A E15431-001               C2M5            
CAP_0603LF-10UF,4V,20%,X6S,E15A E15431-001               C2M10           
CAP_0603LF-10UF,4V,20%,X6S,E15A E15431-001               C2N6            
CAP_0603LF-10UF,4V,20%,X6S,E15A E15431-001               C3A3            
CAP_0603LF-10UF,4V,20%,X6S,E15A E15431-001               C3A4            
CAP_0603LF-10UF,4V,20%,X6S,E15A E15431-001               C3A7            
CAP_0603LF-10UF,4V,20%,X6S,E15A E15431-001               C3A8            
CAP_0603LF-10UF,4V,20%,X6S,E15A E15431-001               C3B1            
CAP_0603LF-10UF,4V,20%,X6S,E15A E15431-001               C3B2            
CAP_0603LF-10UF,4V,20%,X6S,E15A E15431-001               C3D3            
CAP_0603LF-10UF,4V,20%,X6S,E15A E15431-001               C3F3            
CAP_0603LF-10UF,4V,20%,X6S,E15A E15431-001               C3F4            
CAP_0603LF-10UF,4V,20%,X6S,E15A E15431-001               C3G3            
CAP_0603LF-10UF,4V,20%,X6S,E15A E15431-001               C3G4            
CAP_0603LF-10UF,4V,20%,X6S,E15A E15431-001               C3G7            
CAP_0603LF-10UF,4V,20%,X6S,E15A E15431-001               C3G8            
CAP_0603LF-10UF,4V,20%,X6S,E15A E15431-001               C3M17           
CAP_0603LF-10UF,4V,20%,X6S,E15A E15431-001               C3M18           
CAP_0603LF-10UF,4V,20%,X6S,E15A E15431-001               C3M23           
CAP_0603LF-10UF,4V,20%,X6S,E15A E15431-001               C3M24           
CAP_0603LF-10UF,4V,20%,X6S,E15A E15431-001               C4A15           
CAP_0603LF-10UF,4V,20%,X6S,E15A E15431-001               C4L1            
CAP_0603LF-10UF,4V,20%,X6S,E15A E15431-001               C4L2            
CAP_0603LF-10UF,4V,20%,X6S,E15A E15431-001               C4L3            
CAP_0603LF-10UF,4V,20%,X6S,E15A E15431-001               C4L4            
CAP_0603LF-10UF,4V,20%,X6S,E15A E15431-001               C4M3            
CAP_0603LF-10UF,4V,20%,X6S,E15A E15431-001               C4M4            
CAP_0603LF-10UF,4V,20%,X6S,E15A E15431-001               C4T5            
CAP_0603LF-10UF,4V,20%,X6S,E15A E15431-001               C4T6            
CAP_0603LF-10UF,4V,20%,X6S,E15A E15431-001               C4U1            
CAP_0603LF-10UF,4V,20%,X6S,E15A E15431-001               C4U2            
CAP_0603LF-10UF,4V,20%,X6S,E15A E15431-001               C4U3            
CAP_0603LF-10UF,4V,20%,X6S,E15A E15431-001               C4U4            
CAP_0603LF-10UF,4V,20%,X6S,E15A E15431-001               C5D6            
CAP_0603LF-10UF,4V,20%,X6S,E15A E15431-001               C5D7            
CAP_0603LF-10UF,4V,20%,X6S,E15A E15431-001               C5D8            
CAP_0603LF-10UF,4V,20%,X6S,E15A E15431-001               C5D9            
CAP_0603LF-10UF,4V,20%,X6S,E15A E15431-001               C5D10           
CAP_0603LF-10UF,4V,20%,X6S,E15A E15431-001               C5D11           
CAP_0603LF-10UF,4V,20%,X6S,E15A E15431-001               C5D12           
CAP_0603LF-10UF,4V,20%,X6S,E15A E15431-001               C5D13           
CAP_0603LF-10UF,4V,20%,X6S,E15A E15431-001               C5D54           
CAP_0603LF-10UF,4V,20%,X6S,E15A E15431-001               C5D55           
CAP_0603LF-10UF,4V,20%,X6S,E15A E15431-001               C5D56           
CAP_0603LF-10UF,4V,20%,X6S,E15A E15431-001               C5D57           
CAP_0603LF-10UF,4V,20%,X6S,E15A E15431-001               C6A2            
CAP_0603LF-10UF,4V,20%,X6S,E15A E15431-001               C6A3            
CAP_0603LF-10UF,4V,20%,X6S,E15A E15431-001               C6A6            
CAP_0603LF-10UF,4V,20%,X6S,E15A E15431-001               C6A7            
CAP_0603LF-10UF,4V,20%,X6S,E15A E15431-001               C6B1            
CAP_0603LF-10UF,4V,20%,X6S,E15A E15431-001               C6B2            
CAP_0603LF-10UF,4V,20%,X6S,E15A E15431-001               C6D1            
CAP_0603LF-10UF,4V,20%,X6S,E15A E15431-001               C6F5            
CAP_0603LF-10UF,4V,20%,X6S,E15A E15431-001               C6F6            
CAP_0603LF-10UF,4V,20%,X6S,E15A E15431-001               C6G1            
CAP_0603LF-10UF,4V,20%,X6S,E15A E15431-001               C6G2            
CAP_0603LF-10UF,4V,20%,X6S,E15A E15431-001               C6G4            
CAP_0603LF-10UF,4V,20%,X6S,E15A E15431-001               C6G5            
CAP_0603LF-10UF,4V,20%,X6S,E15A E15431-001               C6L3            
CAP_0603LF-10UF,4V,20%,X6S,E15A E15431-001               C6L4            
CAP_0603LF-10UF,4V,20%,X6S,E15A E15431-001               C6L5            
CAP_0603LF-10UF,4V,20%,X6S,E15A E15431-001               C6U13           
CAP_0603LF-10UF,4V,20%,X6S,E15A E15431-001               C6U14           
CAP_0603LF-10UF,4V,20%,X6S,E15A E15431-001               C6U15           
CAP_0603LF-10UF,4V,20%,X6S,E15A E15431-001               C6U16           
CAP_0603LF-10UF,4V,20%,X6S,E15A E15431-001               C7L2            
CAP_0603LF-10UF,4V,20%,X6S,E15A E15431-001               C7L3            
CAP_0603LF-10UF,4V,20%,X6S,E15A E15431-001               C7L6            
CAP_0603LF-10UF,4V,20%,X6S,E15A E15431-001               C7L7            
CAP_0603LF-10UF,4V,20%,X6S,E15A E15431-001               C7M3            
CAP_0603LF-10UF,4V,20%,X6S,E15A E15431-001               C7M4            
CAP_0603LF-10UF,4V,20%,X6S,E15A E15431-001               C7T2            
CAP_0603LF-10UF,4V,20%,X6S,E15A E15431-001               C7T3            
CAP_0603LF-10UF,4V,20%,X6S,E15A E15431-001               C7U3            
CAP_0603LF-10UF,4V,20%,X6S,E15A E15431-001               C7U4            
CAP_0603LF-10UF,4V,20%,X6S,E15A E15431-001               C7U5            
CAP_0603LF-10UF,4V,20%,X6S,E15A E15431-001               C7U6            

----------------

CAP_0805-100UF,4V,20%,X5R,6024A 602433-112               C2A8            
CAP_0805-100UF,4V,20%,X5R,6024A 602433-112               C2A16           
CAP_0805-100UF,4V,20%,X5R,6024A 602433-112               C2G7            
CAP_0805-100UF,4V,20%,X5R,6024A 602433-112               C2G16           
CAP_0805-100UF,4V,20%,X5R,6024A 602433-112               C4T4            
CAP_0805-100UF,4V,20%,X5R,6024A 602433-112               C5A10           
CAP_0805-100UF,4V,20%,X5R,6024A 602433-112               C5A20           
CAP_0805-100UF,4V,20%,X5R,6024A 602433-112               C5G9            
CAP_0805-100UF,4V,20%,X5R,6024A 602433-112               C5G20           
CAP_0805-100UF,4V,20%,X5R,6024A 602433-112               C5G21           
CAP_0805-100UF,4V,20%,X5R,6024A 602433-112               C5G22           
CAP_0805-100UF,4V,20%,X5R,6024A 602433-112               C5G77           
CAP_0805-100UF,4V,20%,X5R,6024A 602433-112               C5G78           
CAP_0805-100UF,4V,20%,X5R,6024A 602433-112               C5G115          
CAP_0805-100UF,4V,20%,X5R,6024A 602433-112               C5G116          
CAP_0805-100UF,4V,20%,X5R,6024A 602433-112               C5G117          
CAP_0805-100UF,4V,20%,X5R,6024A 602433-112               C5G118          
CAP_0805-100UF,4V,20%,X5R,6024A 602433-112               C5L1            
CAP_0805-100UF,4V,20%,X5R,6024A 602433-112               C5L2            
CAP_0805-100UF,4V,20%,X5R,6024A 602433-112               C5L3            
CAP_0805-100UF,4V,20%,X5R,6024A 602433-112               C5L14           
CAP_0805-100UF,4V,20%,X5R,6024A 602433-112               C5M8            
CAP_0805-100UF,4V,20%,X5R,6024A 602433-112               C5M12           
CAP_0805-100UF,4V,20%,X5R,6024A 602433-112               C5U1            
CAP_0805-100UF,4V,20%,X5R,6024A 602433-112               C5U10           
CAP_0805-100UF,4V,20%,X5R,6024A 602433-112               C5U13           
CAP_0805-100UF,4V,20%,X5R,6024A 602433-112               C5U14           
CAP_0805-100UF,4V,20%,X5R,6024A 602433-112               C5U15           
CAP_0805-100UF,4V,20%,X5R,6024A 602433-112               C7L1            
CAP_0805-100UF,4V,20%,X5R,6024A 602433-112               C7T1            
CAP_0805-100UF,4V,20%,X5R,6024A 602433-112               C7U7            
CAP_0805-100UF,4V,20%,X5R,6024A 602433-112               C8L1            
CAP_0805-100UF,4V,20%,X5R,6024A 602433-112               C8L2            
CAP_0805-100UF,4V,20%,X5R,6024A 602433-112               C8L11           
CAP_0805-100UF,4V,20%,X5R,6024A 602433-112               C8M7            
CAP_0805-100UF,4V,20%,X5R,6024A 602433-112               C8M11           
CAP_0805-100UF,4V,20%,X5R,6024A 602433-112               C8U1            
CAP_0805-100UF,4V,20%,X5R,6024A 602433-112               C8U8            
CAP_0805-100UF,4V,20%,X5R,6024A 602433-112               C8U11           
CAP_0805-100UF,4V,20%,X5R,6024A 602433-112               C8U12           

----------------

CAP_0805-10UF,16V,10%,X6S,C953A C95333-007               C1B18           
CAP_0805-10UF,16V,10%,X6S,C953A C95333-007               C1E12           
CAP_0805-10UF,16V,10%,X6S,C953A C95333-007               C1E15           
CAP_0805-10UF,16V,10%,X6S,C953A C95333-007               C1E21           
CAP_0805-10UF,16V,10%,X6S,C953A C95333-007               C1M26           
CAP_0805-10UF,16V,10%,X6S,C953A C95333-007               C1M27           
CAP_0805-10UF,16V,10%,X6S,C953A C95333-007               C1U1            
CAP_0805-10UF,16V,10%,X6S,C953A C95333-007               C1U12           
CAP_0805-10UF,16V,10%,X6S,C953A C95333-007               C2T22           
CAP_0805-10UF,16V,10%,X6S,C953A C95333-007               C2U1            
CAP_0805-10UF,16V,10%,X6S,C953A C95333-007               C2U2            
CAP_0805-10UF,16V,10%,X6S,C953A C95333-007               C3L2            
CAP_0805-10UF,16V,10%,X6S,C953A C95333-007               C3L4            
CAP_0805-10UF,16V,10%,X6S,C953A C95333-007               C3L7            
CAP_0805-10UF,16V,10%,X6S,C953A C95333-007               C3L8            
CAP_0805-10UF,16V,10%,X6S,C953A C95333-007               C3L9            
CAP_0805-10UF,16V,10%,X6S,C953A C95333-007               C3L10           
CAP_0805-10UF,16V,10%,X6S,C953A C95333-007               C3L11           
CAP_0805-10UF,16V,10%,X6S,C953A C95333-007               C3L12           
CAP_0805-10UF,16V,10%,X6S,C953A C95333-007               C3L13           
CAP_0805-10UF,16V,10%,X6S,C953A C95333-007               C3L15           
CAP_0805-10UF,16V,10%,X6S,C953A C95333-007               C3L16           
CAP_0805-10UF,16V,10%,X6S,C953A C95333-007               C3L17           
CAP_0805-10UF,16V,10%,X6S,C953A C95333-007               C3M8            
CAP_0805-10UF,16V,10%,X6S,C953A C95333-007               C3M15           
CAP_0805-10UF,16V,10%,X6S,C953A C95333-007               C3M16           
CAP_0805-10UF,16V,10%,X6S,C953A C95333-007               C3N33           
CAP_0805-10UF,16V,10%,X6S,C953A C95333-007               C3N34           
CAP_0805-10UF,16V,10%,X6S,C953A C95333-007               C3N36           
CAP_0805-10UF,16V,10%,X6S,C953A C95333-007               C3T8            
CAP_0805-10UF,16V,10%,X6S,C953A C95333-007               C3T12           
CAP_0805-10UF,16V,10%,X6S,C953A C95333-007               C3T14           
CAP_0805-10UF,16V,10%,X6S,C953A C95333-007               C3U2            
CAP_0805-10UF,16V,10%,X6S,C953A C95333-007               C3U3            
CAP_0805-10UF,16V,10%,X6S,C953A C95333-007               C3U4            
CAP_0805-10UF,16V,10%,X6S,C953A C95333-007               C3U6            
CAP_0805-10UF,16V,10%,X6S,C953A C95333-007               C3U7            
CAP_0805-10UF,16V,10%,X6S,C953A C95333-007               C3U9            
CAP_0805-10UF,16V,10%,X6S,C953A C95333-007               C4A19           
CAP_0805-10UF,16V,10%,X6S,C953A C95333-007               C4G2            
CAP_0805-10UF,16V,10%,X6S,C953A C95333-007               C6L10           
CAP_0805-10UF,16V,10%,X6S,C953A C95333-007               C6M3            
CAP_0805-10UF,16V,10%,X6S,C953A C95333-007               C6M5            
CAP_0805-10UF,16V,10%,X6S,C953A C95333-007               C6N2            
CAP_0805-10UF,16V,10%,X6S,C953A C95333-007               C6N3            
CAP_0805-10UF,16V,10%,X6S,C953A C95333-007               C6N6            
CAP_0805-10UF,16V,10%,X6S,C953A C95333-007               C6N8            
CAP_0805-10UF,16V,10%,X6S,C953A C95333-007               C6N10           
CAP_0805-10UF,16V,10%,X6S,C953A C95333-007               C6N11           
CAP_0805-10UF,16V,10%,X6S,C953A C95333-007               C6P7            
CAP_0805-10UF,16V,10%,X6S,C953A C95333-007               C6P13           
CAP_0805-10UF,16V,10%,X6S,C953A C95333-007               C6P15           
CAP_0805-10UF,16V,10%,X6S,C953A C95333-007               C6P17           
CAP_0805-10UF,16V,10%,X6S,C953A C95333-007               C6P19           
CAP_0805-10UF,16V,10%,X6S,C953A C95333-007               C6P20           
CAP_0805-10UF,16V,10%,X6S,C953A C95333-007               C6P22           
CAP_0805-10UF,16V,10%,X6S,C953A C95333-007               C6P24           
CAP_0805-10UF,16V,10%,X6S,C953A C95333-007               C6R4            
CAP_0805-10UF,16V,10%,X6S,C953A C95333-007               C6R6            
CAP_0805-10UF,16V,10%,X6S,C953A C95333-007               C6R8            
CAP_0805-10UF,16V,10%,X6S,C953A C95333-007               C6R10           
CAP_0805-10UF,16V,10%,X6S,C953A C95333-007               C6R11           
CAP_0805-10UF,16V,10%,X6S,C953A C95333-007               C6R13           
CAP_0805-10UF,16V,10%,X6S,C953A C95333-007               C6R14           
CAP_0805-10UF,16V,10%,X6S,C953A C95333-007               C6U4            
CAP_0805-10UF,16V,10%,X6S,C953A C95333-007               C6U7            
CAP_0805-10UF,16V,10%,X6S,C953A C95333-007               C6U8            
CAP_0805-10UF,16V,10%,X6S,C953A C95333-007               C7B5            
CAP_0805-10UF,16V,10%,X6S,C953A C95333-007               C7E6            
CAP_0805-10UF,16V,10%,X6S,C953A C95333-007               C7E8            
CAP_0805-10UF,16V,10%,X6S,C953A C95333-007               C7F5            
CAP_0805-10UF,16V,10%,X6S,C953A C95333-007               C8B6            
CAP_0805-10UF,16V,10%,X6S,C953A C95333-007               C8B12           
CAP_0805-10UF,16V,10%,X6S,C953A C95333-007               C9B1            
CAP_0805-10UF,16V,10%,X6S,C953A C95333-007               C9B2            
CAP_0805-10UF,16V,10%,X6S,C953A C95333-007               C9L5            
CAP_0805-10UF,16V,10%,X6S,C953A C95333-007               C9L6            
CAP_0805-10UF,16V,10%,X6S,C953A C95333-007               C9L10           
CAP_0805-10UF,16V,10%,X6S,C953A C95333-007               C9L11           
CAP_0805-10UF,16V,10%,X6S,C953A C95333-007               C9L13           
CAP_0805-10UF,16V,10%,X6S,C953A C95333-007               C9L14           
CAP_0805-10UF,16V,10%,X6S,C953A C95333-007               C9M4            
CAP_0805-10UF,16V,10%,X6S,C953A C95333-007               C9M10           
CAP_0805-10UF,16V,10%,X6S,C953A C95333-007               C9N13           
CAP_0805-10UF,16V,10%,X6S,C953A C95333-007               C9N19           
CAP_0805-10UF,16V,10%,X6S,C953A C95333-007               C9N21           
CAP_0805-10UF,16V,10%,X6S,C953A C95333-007               C9N25           
CAP_0805-10UF,16V,10%,X6S,C953A C95333-007               C9N26           
CAP_0805-10UF,16V,10%,X6S,C953A C95333-007               C9N27           
CAP_0805-10UF,16V,10%,X6S,C953A C95333-007               C9P1            
CAP_0805-10UF,16V,10%,X6S,C953A C95333-007               C9P2            
CAP_0805-10UF,16V,10%,X6S,C953A C95333-007               C9P4            
CAP_0805-10UF,16V,10%,X6S,C953A C95333-007               C9P7            
CAP_0805-10UF,16V,10%,X6S,C953A C95333-007               C9P9            
CAP_0805-10UF,16V,10%,X6S,C953A C95333-007               C9P22           
CAP_0805-10UF,16V,10%,X6S,C953A C95333-007               C9P24           
CAP_0805-10UF,16V,10%,X6S,C953A C95333-007               C9P25           
CAP_0805-10UF,16V,10%,X6S,C953A C95333-007               C9P26           
CAP_0805-10UF,16V,10%,X6S,C953A C95333-007               C9R5            
CAP_0805-10UF,16V,10%,X6S,C953A C95333-007               C9R7            
CAP_0805-10UF,16V,10%,X6S,C953A C95333-007               C9R10           
CAP_0805-10UF,16V,10%,X6S,C953A C95333-007               C9R11           
CAP_0805-10UF,16V,10%,X6S,C953A C95333-007               C9T4            
CAP_0805-10UF,16V,10%,X6S,C953A C95333-007               C9T6            
CAP_0805-10UF,16V,10%,X6S,C953A C95333-007               C9T9            
CAP_0805-10UF,16V,10%,X6S,C953A C95333-007               C9U3            
CAP_0805-10UF,16V,10%,X6S,C953A C95333-007               C9U4            
CAP_0805-10UF,16V,10%,X6S,C953A C95333-007               C9U6            

----------------

CAP_0805-10UF,16V,10%,X7R,G106A G10601-001               C1A4            
CAP_0805-10UF,16V,10%,X7R,G106A G10601-001               C1A16           
CAP_0805-10UF,16V,10%,X7R,G106A G10601-001               C1B7            
CAP_0805-10UF,16V,10%,X7R,G106A G10601-001               C1U20           
CAP_0805-10UF,16V,10%,X7R,G106A G10601-001               C3D22           
CAP_0805-10UF,16V,10%,X7R,G106A G10601-001               C4A4            
CAP_0805-10UF,16V,10%,X7R,G106A G10601-001               C4A17           
CAP_0805-10UF,16V,10%,X7R,G106A G10601-001               C4B11           
CAP_0805-10UF,16V,10%,X7R,G106A G10601-001               C6T2            
CAP_0805-10UF,16V,10%,X7R,G106A G10601-001               C6U10           
CAP_0805-10UF,16V,10%,X7R,G106A G10601-001               C6U18           
CAP_0805-10UF,16V,10%,X7R,G106A G10601-001               C9T8            
CAP_0805-10UF,16V,10%,X7R,G106A G10601-001               C9U8            
CAP_0805-10UF,16V,10%,X7R,G106A G10601-001               C9U11           

----------------

CAP_0805-22UF,6.3V,20%,X6S,C95A C95333-008               C1T9            
CAP_0805-22UF,6.3V,20%,X6S,C95A C95333-008               C1T13           
CAP_0805-22UF,6.3V,20%,X6S,C95A C95333-008               C2L45           
CAP_0805-22UF,6.3V,20%,X6S,C95A C95333-008               C2T6            
CAP_0805-22UF,6.3V,20%,X6S,C95A C95333-008               C2T7            
CAP_0805-22UF,6.3V,20%,X6S,C95A C95333-008               C2T9            
CAP_0805-22UF,6.3V,20%,X6S,C95A C95333-008               C8A14           
CAP_0805-22UF,6.3V,20%,X6S,C95A C95333-008               C8E7            
CAP_0805-22UF,6.3V,20%,X6S,C95A C95333-008               C8E9            

----------------

CAP_0805-47UF,4V,20%,X6S,C9533A C95333-006               C2L32           
CAP_0805-47UF,4V,20%,X6S,C9533A C95333-006               C2M11           
CAP_0805-47UF,4V,20%,X6S,C9533A C95333-006               C2M17           
CAP_0805-47UF,4V,20%,X6S,C9533A C95333-006               C3T7            
CAP_0805-47UF,4V,20%,X6S,C9533A C95333-006               C3T9            
CAP_0805-47UF,4V,20%,X6S,C9533A C95333-006               C4B2            
CAP_0805-47UF,4V,20%,X6S,C9533A C95333-006               C4B3            
CAP_0805-47UF,4V,20%,X6S,C9533A C95333-006               C4P1            
CAP_0805-47UF,4V,20%,X6S,C9533A C95333-006               C4P2            
CAP_0805-47UF,4V,20%,X6S,C9533A C95333-006               C4P3            
CAP_0805-47UF,4V,20%,X6S,C9533A C95333-006               C4P4            
CAP_0805-47UF,4V,20%,X6S,C9533A C95333-006               C4P5            
CAP_0805-47UF,4V,20%,X6S,C9533A C95333-006               C4P7            
CAP_0805-47UF,4V,20%,X6S,C9533A C95333-006               C4P9            
CAP_0805-47UF,4V,20%,X6S,C9533A C95333-006               C4P10           
CAP_0805-47UF,4V,20%,X6S,C9533A C95333-006               C5P3            
CAP_0805-47UF,4V,20%,X6S,C9533A C95333-006               C5P4            
CAP_0805-47UF,4V,20%,X6S,C9533A C95333-006               C5P5            
CAP_0805-47UF,4V,20%,X6S,C9533A C95333-006               C5P6            
CAP_0805-47UF,4V,20%,X6S,C9533A C95333-006               C5P10           
CAP_0805-47UF,4V,20%,X6S,C9533A C95333-006               C5P11           
CAP_0805-47UF,4V,20%,X6S,C9533A C95333-006               C5P12           
CAP_0805-47UF,4V,20%,X6S,C9533A C95333-006               C5P13           
CAP_0805-47UF,4V,20%,X6S,C9533A C95333-006               C5P14           
CAP_0805-47UF,4V,20%,X6S,C9533A C95333-006               C5P15           
CAP_0805-47UF,4V,20%,X6S,C9533A C95333-006               C5P16           
CAP_0805-47UF,4V,20%,X6S,C9533A C95333-006               C5P17           
CAP_0805-47UF,4V,20%,X6S,C9533A C95333-006               C5P18           
CAP_0805-47UF,4V,20%,X6S,C9533A C95333-006               C5P19           
CAP_0805-47UF,4V,20%,X6S,C9533A C95333-006               C5P20           
CAP_0805-47UF,4V,20%,X6S,C9533A C95333-006               C5P21           
CAP_0805-47UF,4V,20%,X6S,C9533A C95333-006               C5P22           
CAP_0805-47UF,4V,20%,X6S,C9533A C95333-006               C5P23           
CAP_0805-47UF,4V,20%,X6S,C9533A C95333-006               C5P24           
CAP_0805-47UF,4V,20%,X6S,C9533A C95333-006               C5P25           
CAP_0805-47UF,4V,20%,X6S,C9533A C95333-006               C5P26           
CAP_0805-47UF,4V,20%,X6S,C9533A C95333-006               C5P27           
CAP_0805-47UF,4V,20%,X6S,C9533A C95333-006               C5P28           
CAP_0805-47UF,4V,20%,X6S,C9533A C95333-006               C5P29           
CAP_0805-47UF,4V,20%,X6S,C9533A C95333-006               C5P30           
CAP_0805-47UF,4V,20%,X6S,C9533A C95333-006               C5P31           
CAP_0805-47UF,4V,20%,X6S,C9533A C95333-006               C5P32           
CAP_0805-47UF,4V,20%,X6S,C9533A C95333-006               C5P33           
CAP_0805-47UF,4V,20%,X6S,C9533A C95333-006               C5P34           
CAP_0805-47UF,4V,20%,X6S,C9533A C95333-006               C5P35           
CAP_0805-47UF,4V,20%,X6S,C9533A C95333-006               C5P36           
CAP_0805-47UF,4V,20%,X6S,C9533A C95333-006               C5P37           
CAP_0805-47UF,4V,20%,X6S,C9533A C95333-006               C5P40           
CAP_0805-47UF,4V,20%,X6S,C9533A C95333-006               C5P41           
CAP_0805-47UF,4V,20%,X6S,C9533A C95333-006               C5P42           
CAP_0805-47UF,4V,20%,X6S,C9533A C95333-006               C5P43           
CAP_0805-47UF,4V,20%,X6S,C9533A C95333-006               C5P44           
CAP_0805-47UF,4V,20%,X6S,C9533A C95333-006               C6B3            
CAP_0805-47UF,4V,20%,X6S,C9533A C95333-006               C6U2            
CAP_0805-47UF,4V,20%,X6S,C9533A C95333-006               C6U3            
CAP_0805-47UF,4V,20%,X6S,C9533A C95333-006               C7A31           
CAP_0805-47UF,4V,20%,X6S,C9533A C95333-006               C7A32           
CAP_0805-47UF,4V,20%,X6S,C9533A C95333-006               C7A33           
CAP_0805-47UF,4V,20%,X6S,C9533A C95333-006               C7B4            
CAP_0805-47UF,4V,20%,X6S,C9533A C95333-006               C7B7            
CAP_0805-47UF,4V,20%,X6S,C9533A C95333-006               C7P1            
CAP_0805-47UF,4V,20%,X6S,C9533A C95333-006               C7P2            
CAP_0805-47UF,4V,20%,X6S,C9533A C95333-006               C7P3            
CAP_0805-47UF,4V,20%,X6S,C9533A C95333-006               C7P4            
CAP_0805-47UF,4V,20%,X6S,C9533A C95333-006               C7P5            
CAP_0805-47UF,4V,20%,X6S,C9533A C95333-006               C7P6            
CAP_0805-47UF,4V,20%,X6S,C9533A C95333-006               C7P7            
CAP_0805-47UF,4V,20%,X6S,C9533A C95333-006               C7P8            
CAP_0805-47UF,4V,20%,X6S,C9533A C95333-006               C7P9            
CAP_0805-47UF,4V,20%,X6S,C9533A C95333-006               C7P10           
CAP_0805-47UF,4V,20%,X6S,C9533A C95333-006               C7P11           
CAP_0805-47UF,4V,20%,X6S,C9533A C95333-006               C7P13           
CAP_0805-47UF,4V,20%,X6S,C9533A C95333-006               C7P14           
CAP_0805-47UF,4V,20%,X6S,C9533A C95333-006               C7P15           
CAP_0805-47UF,4V,20%,X6S,C9533A C95333-006               C7P17           
CAP_0805-47UF,4V,20%,X6S,C9533A C95333-006               C7P18           
CAP_0805-47UF,4V,20%,X6S,C9533A C95333-006               C7P19           
CAP_0805-47UF,4V,20%,X6S,C9533A C95333-006               C7P20           
CAP_0805-47UF,4V,20%,X6S,C9533A C95333-006               C8A12           
CAP_0805-47UF,4V,20%,X6S,C9533A C95333-006               C8A13           
CAP_0805-47UF,4V,20%,X6S,C9533A C95333-006               C8B15           
CAP_0805-47UF,4V,20%,X6S,C9533A C95333-006               C8B16           
CAP_0805-47UF,4V,20%,X6S,C9533A C95333-006               C8P3            
CAP_0805-47UF,4V,20%,X6S,C9533A C95333-006               C8P4            
CAP_0805-47UF,4V,20%,X6S,C9533A C95333-006               C8P8            
CAP_0805-47UF,4V,20%,X6S,C9533A C95333-006               C8P9            
CAP_0805-47UF,4V,20%,X6S,C9533A C95333-006               C8P10           
CAP_0805-47UF,4V,20%,X6S,C9533A C95333-006               C8P11           
CAP_0805-47UF,4V,20%,X6S,C9533A C95333-006               C8P12           
CAP_0805-47UF,4V,20%,X6S,C9533A C95333-006               C8P13           
CAP_0805-47UF,4V,20%,X6S,C9533A C95333-006               C8P14           
CAP_0805-47UF,4V,20%,X6S,C9533A C95333-006               C8P15           
CAP_0805-47UF,4V,20%,X6S,C9533A C95333-006               C8P16           
CAP_0805-47UF,4V,20%,X6S,C9533A C95333-006               C8P17           
CAP_0805-47UF,4V,20%,X6S,C9533A C95333-006               C8P18           
CAP_0805-47UF,4V,20%,X6S,C9533A C95333-006               C8P19           
CAP_0805-47UF,4V,20%,X6S,C9533A C95333-006               C8P20           
CAP_0805-47UF,4V,20%,X6S,C9533A C95333-006               C8P21           
CAP_0805-47UF,4V,20%,X6S,C9533A C95333-006               C8P22           
CAP_0805-47UF,4V,20%,X6S,C9533A C95333-006               C8P23           
CAP_0805-47UF,4V,20%,X6S,C9533A C95333-006               C8P24           
CAP_0805-47UF,4V,20%,X6S,C9533A C95333-006               C8P25           
CAP_0805-47UF,4V,20%,X6S,C9533A C95333-006               C8P26           
CAP_0805-47UF,4V,20%,X6S,C9533A C95333-006               C8P27           
CAP_0805-47UF,4V,20%,X6S,C9533A C95333-006               C8P28           
CAP_0805-47UF,4V,20%,X6S,C9533A C95333-006               C8P29           
CAP_0805-47UF,4V,20%,X6S,C9533A C95333-006               C8P32           
CAP_0805-47UF,4V,20%,X6S,C9533A C95333-006               C8P33           
CAP_0805-47UF,4V,20%,X6S,C9533A C95333-006               C8P34           

----------------

CAP_0805LF-22UF,4V,20%,X6S,C95A C95333-002               C1A1            
CAP_0805LF-22UF,4V,20%,X6S,C95A C95333-002               C1A12           
CAP_0805LF-22UF,4V,20%,X6S,C95A C95333-002               C1G17           
CAP_0805LF-22UF,4V,20%,X6S,C95A C95333-002               C1G20           
CAP_0805LF-22UF,4V,20%,X6S,C95A C95333-002               C4A1            
CAP_0805LF-22UF,4V,20%,X6S,C95A C95333-002               C4A13           
CAP_0805LF-22UF,4V,20%,X6S,C95A C95333-002               C4G20           
CAP_0805LF-22UF,4V,20%,X6S,C95A C95333-002               C4G24           
CAP_0805LF-22UF,4V,20%,X6S,C95A C95333-002               C5P1            
CAP_0805LF-22UF,4V,20%,X6S,C95A C95333-002               C5P2            
CAP_0805LF-22UF,4V,20%,X6S,C95A C95333-002               C5P7            
CAP_0805LF-22UF,4V,20%,X6S,C95A C95333-002               C5P8            
CAP_0805LF-22UF,4V,20%,X6S,C95A C95333-002               C5P9            
CAP_0805LF-22UF,4V,20%,X6S,C95A C95333-002               C5P38           
CAP_0805LF-22UF,4V,20%,X6S,C95A C95333-002               C5P39           
CAP_0805LF-22UF,4V,20%,X6S,C95A C95333-002               C6A1            
CAP_0805LF-22UF,4V,20%,X6S,C95A C95333-002               C6A4            
CAP_0805LF-22UF,4V,20%,X6S,C95A C95333-002               C6G3            
CAP_0805LF-22UF,4V,20%,X6S,C95A C95333-002               C7A30           
CAP_0805LF-22UF,4V,20%,X6S,C95A C95333-002               C7A42           
CAP_0805LF-22UF,4V,20%,X6S,C95A C95333-002               C7G27           
CAP_0805LF-22UF,4V,20%,X6S,C95A C95333-002               C8P1            
CAP_0805LF-22UF,4V,20%,X6S,C95A C95333-002               C8P2            
CAP_0805LF-22UF,4V,20%,X6S,C95A C95333-002               C8P5            
CAP_0805LF-22UF,4V,20%,X6S,C95A C95333-002               C8P6            
CAP_0805LF-22UF,4V,20%,X6S,C95A C95333-002               C8P7            
CAP_0805LF-22UF,4V,20%,X6S,C95A C95333-002               C8P30           
CAP_0805LF-22UF,4V,20%,X6S,C95A C95333-002               C8P31           
CAP_0805LF-22UF,4V,20%,X6S,C95A C95333-002               C9F4            
CAP_0805LF-22UF,4V,20%,X6S,C95A C95333-002               C9F13           

----------------

CAP_1206-0.068UF,50V,20%,X7R,1A 108427-047               C1E2            

----------------

CAP_1206LF-22UF,16V,10%,X6S,D3A D38464-005               C2P10           
CAP_1206LF-22UF,16V,10%,X6S,D3A D38464-005               C7E11           
CAP_1206LF-22UF,16V,10%,X6S,D3A D38464-005               C8E10           

----------------

CAP_1210-100UF,16V,20%,X5R,644A 644066-127               C4E8            
CAP_1210-100UF,16V,20%,X5R,644A 644066-127               C4E9            
CAP_1210-100UF,16V,20%,X5R,644A 644066-127               C4E14           
CAP_1210-100UF,16V,20%,X5R,644A 644066-127               C7A13           
CAP_1210-100UF,16V,20%,X5R,644A 644066-127               C7A14           
CAP_1210-100UF,16V,20%,X5R,644A 644066-127               C7C7            
CAP_1210-100UF,16V,20%,X5R,644A 644066-127               C7C8            

----------------

CAP_1210-47UF,16V,20%,EMPTY,D3A D38464-007               C9E6            
CAP_1210-47UF,16V,20%,EMPTY,D3A D38464-007               C9F2            

----------------

CAP_1210-47UF,16V,20%,X6S,D384A D38464-007               C1G2            
CAP_1210-47UF,16V,20%,X6S,D384A D38464-007               C1G7            
CAP_1210-47UF,16V,20%,X6S,D384A D38464-007               C1G12           
CAP_1210-47UF,16V,20%,X6S,D384A D38464-007               C1G15           
CAP_1210-47UF,16V,20%,X6S,D384A D38464-007               C4B1            
CAP_1210-47UF,16V,20%,X6S,D384A D38464-007               C4G5            
CAP_1210-47UF,16V,20%,X6S,D384A D38464-007               C7B8            
CAP_1210-47UF,16V,20%,X6S,D384A D38464-007               C7E12           
CAP_1210-47UF,16V,20%,X6S,D384A D38464-007               C7E13           
CAP_1210-47UF,16V,20%,X6S,D384A D38464-007               C7F7            
CAP_1210-47UF,16V,20%,X6S,D384A D38464-007               C8E11           
CAP_1210-47UF,16V,20%,X6S,D384A D38464-007               C9F1            

----------------

CAP_A_0402V-0.01UF,25V,10%,EMPA A36096-045               C8F6            
CAP_A_0402V-0.01UF,25V,10%,EMPA A36096-045               C8F11           
CAP_A_0402V-0.01UF,25V,10%,EMPA A36096-045               C8F13           
CAP_A_0402V-0.01UF,25V,10%,EMPA A36096-045               C8F15           

----------------

CAP_A_0402V-0.01UF,25V,10%,X7RA A36096-045               C1A5            
CAP_A_0402V-0.01UF,25V,10%,X7RA A36096-045               C1A17           
CAP_A_0402V-0.01UF,25V,10%,X7RA A36096-045               C1B9            
CAP_A_0402V-0.01UF,25V,10%,X7RA A36096-045               C1B15           
CAP_A_0402V-0.01UF,25V,10%,X7RA A36096-045               C1B17           
CAP_A_0402V-0.01UF,25V,10%,X7RA A36096-045               C1F9            
CAP_A_0402V-0.01UF,25V,10%,X7RA A36096-045               C1F19           
CAP_A_0402V-0.01UF,25V,10%,X7RA A36096-045               C1F22           
CAP_A_0402V-0.01UF,25V,10%,X7RA A36096-045               C1G8            
CAP_A_0402V-0.01UF,25V,10%,X7RA A36096-045               C1G10           
CAP_A_0402V-0.01UF,25V,10%,X7RA A36096-045               C1G18           
CAP_A_0402V-0.01UF,25V,10%,X7RA A36096-045               C1G19           
CAP_A_0402V-0.01UF,25V,10%,X7RA A36096-045               C1L2            
CAP_A_0402V-0.01UF,25V,10%,X7RA A36096-045               C1L3            
CAP_A_0402V-0.01UF,25V,10%,X7RA A36096-045               C1L6            
CAP_A_0402V-0.01UF,25V,10%,X7RA A36096-045               C1L7            
CAP_A_0402V-0.01UF,25V,10%,X7RA A36096-045               C1L12           
CAP_A_0402V-0.01UF,25V,10%,X7RA A36096-045               C1L13           
CAP_A_0402V-0.01UF,25V,10%,X7RA A36096-045               C1L14           
CAP_A_0402V-0.01UF,25V,10%,X7RA A36096-045               C1L15           
CAP_A_0402V-0.01UF,25V,10%,X7RA A36096-045               C1L20           
CAP_A_0402V-0.01UF,25V,10%,X7RA A36096-045               C1M28           
CAP_A_0402V-0.01UF,25V,10%,X7RA A36096-045               C1M30           
CAP_A_0402V-0.01UF,25V,10%,X7RA A36096-045               C1M31           
CAP_A_0402V-0.01UF,25V,10%,X7RA A36096-045               C1M34           
CAP_A_0402V-0.01UF,25V,10%,X7RA A36096-045               C1M35           
CAP_A_0402V-0.01UF,25V,10%,X7RA A36096-045               C1M36           
CAP_A_0402V-0.01UF,25V,10%,X7RA A36096-045               C1T24           
CAP_A_0402V-0.01UF,25V,10%,X7RA A36096-045               C1T27           
CAP_A_0402V-0.01UF,25V,10%,X7RA A36096-045               C1T34           
CAP_A_0402V-0.01UF,25V,10%,X7RA A36096-045               C1T36           
CAP_A_0402V-0.01UF,25V,10%,X7RA A36096-045               C1T39           
CAP_A_0402V-0.01UF,25V,10%,X7RA A36096-045               C1T41           
CAP_A_0402V-0.01UF,25V,10%,X7RA A36096-045               C2L3            
CAP_A_0402V-0.01UF,25V,10%,X7RA A36096-045               C2L4            
CAP_A_0402V-0.01UF,25V,10%,X7RA A36096-045               C2L5            
CAP_A_0402V-0.01UF,25V,10%,X7RA A36096-045               C2L6            
CAP_A_0402V-0.01UF,25V,10%,X7RA A36096-045               C2L7            
CAP_A_0402V-0.01UF,25V,10%,X7RA A36096-045               C2L9            
CAP_A_0402V-0.01UF,25V,10%,X7RA A36096-045               C2L10           
CAP_A_0402V-0.01UF,25V,10%,X7RA A36096-045               C2L12           
CAP_A_0402V-0.01UF,25V,10%,X7RA A36096-045               C2L13           
CAP_A_0402V-0.01UF,25V,10%,X7RA A36096-045               C2L14           
CAP_A_0402V-0.01UF,25V,10%,X7RA A36096-045               C2L15           
CAP_A_0402V-0.01UF,25V,10%,X7RA A36096-045               C2L16           
CAP_A_0402V-0.01UF,25V,10%,X7RA A36096-045               C2L17           
CAP_A_0402V-0.01UF,25V,10%,X7RA A36096-045               C2L18           
CAP_A_0402V-0.01UF,25V,10%,X7RA A36096-045               C2L19           
CAP_A_0402V-0.01UF,25V,10%,X7RA A36096-045               C2L20           
CAP_A_0402V-0.01UF,25V,10%,X7RA A36096-045               C2L21           
CAP_A_0402V-0.01UF,25V,10%,X7RA A36096-045               C2L22           
CAP_A_0402V-0.01UF,25V,10%,X7RA A36096-045               C2L23           
CAP_A_0402V-0.01UF,25V,10%,X7RA A36096-045               C2L24           
CAP_A_0402V-0.01UF,25V,10%,X7RA A36096-045               C2L26           
CAP_A_0402V-0.01UF,25V,10%,X7RA A36096-045               C2L27           
CAP_A_0402V-0.01UF,25V,10%,X7RA A36096-045               C2L28           
CAP_A_0402V-0.01UF,25V,10%,X7RA A36096-045               C2L29           
CAP_A_0402V-0.01UF,25V,10%,X7RA A36096-045               C2L30           
CAP_A_0402V-0.01UF,25V,10%,X7RA A36096-045               C2L31           
CAP_A_0402V-0.01UF,25V,10%,X7RA A36096-045               C2L33           
CAP_A_0402V-0.01UF,25V,10%,X7RA A36096-045               C2L34           
CAP_A_0402V-0.01UF,25V,10%,X7RA A36096-045               C2L35           
CAP_A_0402V-0.01UF,25V,10%,X7RA A36096-045               C2L36           
CAP_A_0402V-0.01UF,25V,10%,X7RA A36096-045               C2L37           
CAP_A_0402V-0.01UF,25V,10%,X7RA A36096-045               C2L38           
CAP_A_0402V-0.01UF,25V,10%,X7RA A36096-045               C2L39           
CAP_A_0402V-0.01UF,25V,10%,X7RA A36096-045               C2L40           
CAP_A_0402V-0.01UF,25V,10%,X7RA A36096-045               C2L41           
CAP_A_0402V-0.01UF,25V,10%,X7RA A36096-045               C2L42           
CAP_A_0402V-0.01UF,25V,10%,X7RA A36096-045               C2L43           
CAP_A_0402V-0.01UF,25V,10%,X7RA A36096-045               C2L44           
CAP_A_0402V-0.01UF,25V,10%,X7RA A36096-045               C2L47           
CAP_A_0402V-0.01UF,25V,10%,X7RA A36096-045               C2L48           
CAP_A_0402V-0.01UF,25V,10%,X7RA A36096-045               C2L49           
CAP_A_0402V-0.01UF,25V,10%,X7RA A36096-045               C2L50           
CAP_A_0402V-0.01UF,25V,10%,X7RA A36096-045               C2L51           
CAP_A_0402V-0.01UF,25V,10%,X7RA A36096-045               C2L52           
CAP_A_0402V-0.01UF,25V,10%,X7RA A36096-045               C2P8            
CAP_A_0402V-0.01UF,25V,10%,X7RA A36096-045               C2T18           
CAP_A_0402V-0.01UF,25V,10%,X7RA A36096-045               C2T27           
CAP_A_0402V-0.01UF,25V,10%,X7RA A36096-045               C2T37           
CAP_A_0402V-0.01UF,25V,10%,X7RA A36096-045               C3T5            
CAP_A_0402V-0.01UF,25V,10%,X7RA A36096-045               C4A5            
CAP_A_0402V-0.01UF,25V,10%,X7RA A36096-045               C4A18           
CAP_A_0402V-0.01UF,25V,10%,X7RA A36096-045               C4B12           
CAP_A_0402V-0.01UF,25V,10%,X7RA A36096-045               C4F9            
CAP_A_0402V-0.01UF,25V,10%,X7RA A36096-045               C4F10           
CAP_A_0402V-0.01UF,25V,10%,X7RA A36096-045               C4G1            
CAP_A_0402V-0.01UF,25V,10%,X7RA A36096-045               C4G3            
CAP_A_0402V-0.01UF,25V,10%,X7RA A36096-045               C4G17           
CAP_A_0402V-0.01UF,25V,10%,X7RA A36096-045               C4G19           
CAP_A_0402V-0.01UF,25V,10%,X7RA A36096-045               C6L1            
CAP_A_0402V-0.01UF,25V,10%,X7RA A36096-045               C6L2            
CAP_A_0402V-0.01UF,25V,10%,X7RA A36096-045               C6L6            
CAP_A_0402V-0.01UF,25V,10%,X7RA A36096-045               C6L7            
CAP_A_0402V-0.01UF,25V,10%,X7RA A36096-045               C6M1            
CAP_A_0402V-0.01UF,25V,10%,X7RA A36096-045               C6M2            
CAP_A_0402V-0.01UF,25V,10%,X7RA A36096-045               C6T1            
CAP_A_0402V-0.01UF,25V,10%,X7RA A36096-045               C6U9            
CAP_A_0402V-0.01UF,25V,10%,X7RA A36096-045               C6U17           
CAP_A_0402V-0.01UF,25V,10%,X7RA A36096-045               C7F1            
CAP_A_0402V-0.01UF,25V,10%,X7RA A36096-045               C8F5            
CAP_A_0402V-0.01UF,25V,10%,X7RA A36096-045               C9L1            
CAP_A_0402V-0.01UF,25V,10%,X7RA A36096-045               C9L3            
CAP_A_0402V-0.01UF,25V,10%,X7RA A36096-045               C9L7            
CAP_A_0402V-0.01UF,25V,10%,X7RA A36096-045               C9L8            
CAP_A_0402V-0.01UF,25V,10%,X7RA A36096-045               C9M1            
CAP_A_0402V-0.01UF,25V,10%,X7RA A36096-045               C9M2            
CAP_A_0402V-0.01UF,25V,10%,X7RA A36096-045               C9T1            
CAP_A_0402V-0.01UF,25V,10%,X7RA A36096-045               C9T7            
CAP_A_0402V-0.01UF,25V,10%,X7RA A36096-045               C9U7            
CAP_A_0402V-0.01UF,25V,10%,X7RA A36096-045               C9U10           

----------------

CAP_A_0402V-0.1UF,16V,10%,EMPTA A36096-030               C1B16           
CAP_A_0402V-0.1UF,16V,10%,EMPTA A36096-030               C1D22           
CAP_A_0402V-0.1UF,16V,10%,EMPTA A36096-030               C1T17           
CAP_A_0402V-0.1UF,16V,10%,EMPTA A36096-030               C2M3            
CAP_A_0402V-0.1UF,16V,10%,EMPTA A36096-030               C2M4            
CAP_A_0402V-0.1UF,16V,10%,EMPTA A36096-030               C3D27           
CAP_A_0402V-0.1UF,16V,10%,EMPTA A36096-030               C3P1            
CAP_A_0402V-0.1UF,16V,10%,EMPTA A36096-030               C4C2            
CAP_A_0402V-0.1UF,16V,10%,EMPTA A36096-030               C9F15           
CAP_A_0402V-0.1UF,16V,10%,EMPTA A36096-030               C9F16           
CAP_A_0402V-0.1UF,16V,10%,EMPTA A36096-030               C9F17           
CAP_A_0402V-0.1UF,16V,10%,EMPTA A36096-030               C9G8            
CAP_A_0402V-0.1UF,16V,10%,EMPTA A36096-030               C9G10           
CAP_A_0402V-0.1UF,16V,10%,EMPTA A36096-030               C9G11           
CAP_A_0402V-0.1UF,16V,10%,EMPTA A36096-030               C9P12           
CAP_A_0402V-0.1UF,16V,10%,EMPTA A36096-030               C9P16           
CAP_A_0402V-0.1UF,16V,10%,EMPTA A36096-030               C9P17           

----------------

CAP_A_0402V-0.1UF,16V,10%,X7R,A A36096-030               C1A10           
CAP_A_0402V-0.1UF,16V,10%,X7R,A A36096-030               C1A20           
CAP_A_0402V-0.1UF,16V,10%,X7R,A A36096-030               C1B2            
CAP_A_0402V-0.1UF,16V,10%,X7R,A A36096-030               C1B5            
CAP_A_0402V-0.1UF,16V,10%,X7R,A A36096-030               C1B19           
CAP_A_0402V-0.1UF,16V,10%,X7R,A A36096-030               C1C9            
CAP_A_0402V-0.1UF,16V,10%,X7R,A A36096-030               C1C14           
CAP_A_0402V-0.1UF,16V,10%,X7R,A A36096-030               C1C17           
CAP_A_0402V-0.1UF,16V,10%,X7R,A A36096-030               C1C25           
CAP_A_0402V-0.1UF,16V,10%,X7R,A A36096-030               C1D9            
CAP_A_0402V-0.1UF,16V,10%,X7R,A A36096-030               C1D11           
CAP_A_0402V-0.1UF,16V,10%,X7R,A A36096-030               C1D13           
CAP_A_0402V-0.1UF,16V,10%,X7R,A A36096-030               C1D21           
CAP_A_0402V-0.1UF,16V,10%,X7R,A A36096-030               C1D26           
CAP_A_0402V-0.1UF,16V,10%,X7R,A A36096-030               C1D27           
CAP_A_0402V-0.1UF,16V,10%,X7R,A A36096-030               C1D28           
CAP_A_0402V-0.1UF,16V,10%,X7R,A A36096-030               C1D34           
CAP_A_0402V-0.1UF,16V,10%,X7R,A A36096-030               C1E14           
CAP_A_0402V-0.1UF,16V,10%,X7R,A A36096-030               C1E16           
CAP_A_0402V-0.1UF,16V,10%,X7R,A A36096-030               C1E17           
CAP_A_0402V-0.1UF,16V,10%,X7R,A A36096-030               C1E20           
CAP_A_0402V-0.1UF,16V,10%,X7R,A A36096-030               C1E22           
CAP_A_0402V-0.1UF,16V,10%,X7R,A A36096-030               C1F28           
CAP_A_0402V-0.1UF,16V,10%,X7R,A A36096-030               C1G14           
CAP_A_0402V-0.1UF,16V,10%,X7R,A A36096-030               C1G22           
CAP_A_0402V-0.1UF,16V,10%,X7R,A A36096-030               C1G25           
CAP_A_0402V-0.1UF,16V,10%,X7R,A A36096-030               C1L4            
CAP_A_0402V-0.1UF,16V,10%,X7R,A A36096-030               C1L8            
CAP_A_0402V-0.1UF,16V,10%,X7R,A A36096-030               C1L9            
CAP_A_0402V-0.1UF,16V,10%,X7R,A A36096-030               C1L11           
CAP_A_0402V-0.1UF,16V,10%,X7R,A A36096-030               C1L16           
CAP_A_0402V-0.1UF,16V,10%,X7R,A A36096-030               C1L17           
CAP_A_0402V-0.1UF,16V,10%,X7R,A A36096-030               C1M1            
CAP_A_0402V-0.1UF,16V,10%,X7R,A A36096-030               C1M2            
CAP_A_0402V-0.1UF,16V,10%,X7R,A A36096-030               C1M20           
CAP_A_0402V-0.1UF,16V,10%,X7R,A A36096-030               C1M22           
CAP_A_0402V-0.1UF,16V,10%,X7R,A A36096-030               C1M23           
CAP_A_0402V-0.1UF,16V,10%,X7R,A A36096-030               C1M24           
CAP_A_0402V-0.1UF,16V,10%,X7R,A A36096-030               C1M29           
CAP_A_0402V-0.1UF,16V,10%,X7R,A A36096-030               C1M33           
CAP_A_0402V-0.1UF,16V,10%,X7R,A A36096-030               C1M38           
CAP_A_0402V-0.1UF,16V,10%,X7R,A A36096-030               C1R14           
CAP_A_0402V-0.1UF,16V,10%,X7R,A A36096-030               C1R15           
CAP_A_0402V-0.1UF,16V,10%,X7R,A A36096-030               C1R18           
CAP_A_0402V-0.1UF,16V,10%,X7R,A A36096-030               C1R19           
CAP_A_0402V-0.1UF,16V,10%,X7R,A A36096-030               C1R20           
CAP_A_0402V-0.1UF,16V,10%,X7R,A A36096-030               C1R21           
CAP_A_0402V-0.1UF,16V,10%,X7R,A A36096-030               C1R24           
CAP_A_0402V-0.1UF,16V,10%,X7R,A A36096-030               C1R25           
CAP_A_0402V-0.1UF,16V,10%,X7R,A A36096-030               C1R26           
CAP_A_0402V-0.1UF,16V,10%,X7R,A A36096-030               C1R27           
CAP_A_0402V-0.1UF,16V,10%,X7R,A A36096-030               C1R28           
CAP_A_0402V-0.1UF,16V,10%,X7R,A A36096-030               C1R29           
CAP_A_0402V-0.1UF,16V,10%,X7R,A A36096-030               C1R31           
CAP_A_0402V-0.1UF,16V,10%,X7R,A A36096-030               C1T3            
CAP_A_0402V-0.1UF,16V,10%,X7R,A A36096-030               C1T5            
CAP_A_0402V-0.1UF,16V,10%,X7R,A A36096-030               C1T8            
CAP_A_0402V-0.1UF,16V,10%,X7R,A A36096-030               C1T10           
CAP_A_0402V-0.1UF,16V,10%,X7R,A A36096-030               C1T11           
CAP_A_0402V-0.1UF,16V,10%,X7R,A A36096-030               C1T14           
CAP_A_0402V-0.1UF,16V,10%,X7R,A A36096-030               C1T22           
CAP_A_0402V-0.1UF,16V,10%,X7R,A A36096-030               C1T23           
CAP_A_0402V-0.1UF,16V,10%,X7R,A A36096-030               C1T25           
CAP_A_0402V-0.1UF,16V,10%,X7R,A A36096-030               C1T26           
CAP_A_0402V-0.1UF,16V,10%,X7R,A A36096-030               C1T29           
CAP_A_0402V-0.1UF,16V,10%,X7R,A A36096-030               C1T30           
CAP_A_0402V-0.1UF,16V,10%,X7R,A A36096-030               C1T33           
CAP_A_0402V-0.1UF,16V,10%,X7R,A A36096-030               C1T37           
CAP_A_0402V-0.1UF,16V,10%,X7R,A A36096-030               C1T38           
CAP_A_0402V-0.1UF,16V,10%,X7R,A A36096-030               C1T40           
CAP_A_0402V-0.1UF,16V,10%,X7R,A A36096-030               C1T43           
CAP_A_0402V-0.1UF,16V,10%,X7R,A A36096-030               C1T45           
CAP_A_0402V-0.1UF,16V,10%,X7R,A A36096-030               C1T47           
CAP_A_0402V-0.1UF,16V,10%,X7R,A A36096-030               C1T48           
CAP_A_0402V-0.1UF,16V,10%,X7R,A A36096-030               C1T50           
CAP_A_0402V-0.1UF,16V,10%,X7R,A A36096-030               C1T52           
CAP_A_0402V-0.1UF,16V,10%,X7R,A A36096-030               C1T53           
CAP_A_0402V-0.1UF,16V,10%,X7R,A A36096-030               C1T54           
CAP_A_0402V-0.1UF,16V,10%,X7R,A A36096-030               C1T56           
CAP_A_0402V-0.1UF,16V,10%,X7R,A A36096-030               C1U3            
CAP_A_0402V-0.1UF,16V,10%,X7R,A A36096-030               C1U4            
CAP_A_0402V-0.1UF,16V,10%,X7R,A A36096-030               C1U5            
CAP_A_0402V-0.1UF,16V,10%,X7R,A A36096-030               C1U9            
CAP_A_0402V-0.1UF,16V,10%,X7R,A A36096-030               C1U10           
CAP_A_0402V-0.1UF,16V,10%,X7R,A A36096-030               C1U11           
CAP_A_0402V-0.1UF,16V,10%,X7R,A A36096-030               C1U13           
CAP_A_0402V-0.1UF,16V,10%,X7R,A A36096-030               C1U14           
CAP_A_0402V-0.1UF,16V,10%,X7R,A A36096-030               C1U15           
CAP_A_0402V-0.1UF,16V,10%,X7R,A A36096-030               C1U16           
CAP_A_0402V-0.1UF,16V,10%,X7R,A A36096-030               C1U22           
CAP_A_0402V-0.1UF,16V,10%,X7R,A A36096-030               C2L11           
CAP_A_0402V-0.1UF,16V,10%,X7R,A A36096-030               C2M23           
CAP_A_0402V-0.1UF,16V,10%,X7R,A A36096-030               C2M24           
CAP_A_0402V-0.1UF,16V,10%,X7R,A A36096-030               C2P1            
CAP_A_0402V-0.1UF,16V,10%,X7R,A A36096-030               C2P2            
CAP_A_0402V-0.1UF,16V,10%,X7R,A A36096-030               C2P3            
CAP_A_0402V-0.1UF,16V,10%,X7R,A A36096-030               C2P4            
CAP_A_0402V-0.1UF,16V,10%,X7R,A A36096-030               C2P5            
CAP_A_0402V-0.1UF,16V,10%,X7R,A A36096-030               C2P6            
CAP_A_0402V-0.1UF,16V,10%,X7R,A A36096-030               C2P7            
CAP_A_0402V-0.1UF,16V,10%,X7R,A A36096-030               C2P9            
CAP_A_0402V-0.1UF,16V,10%,X7R,A A36096-030               C2P11           
CAP_A_0402V-0.1UF,16V,10%,X7R,A A36096-030               C2P12           
CAP_A_0402V-0.1UF,16V,10%,X7R,A A36096-030               C2P13           
CAP_A_0402V-0.1UF,16V,10%,X7R,A A36096-030               C2P14           
CAP_A_0402V-0.1UF,16V,10%,X7R,A A36096-030               C2P15           
CAP_A_0402V-0.1UF,16V,10%,X7R,A A36096-030               C2P16           
CAP_A_0402V-0.1UF,16V,10%,X7R,A A36096-030               C2R1            
CAP_A_0402V-0.1UF,16V,10%,X7R,A A36096-030               C2R2            
CAP_A_0402V-0.1UF,16V,10%,X7R,A A36096-030               C2R3            
CAP_A_0402V-0.1UF,16V,10%,X7R,A A36096-030               C2R4            
CAP_A_0402V-0.1UF,16V,10%,X7R,A A36096-030               C2R5            
CAP_A_0402V-0.1UF,16V,10%,X7R,A A36096-030               C2R15           
CAP_A_0402V-0.1UF,16V,10%,X7R,A A36096-030               C2R16           
CAP_A_0402V-0.1UF,16V,10%,X7R,A A36096-030               C2R17           
CAP_A_0402V-0.1UF,16V,10%,X7R,A A36096-030               C2R18           
CAP_A_0402V-0.1UF,16V,10%,X7R,A A36096-030               C2T1            
CAP_A_0402V-0.1UF,16V,10%,X7R,A A36096-030               C2T2            
CAP_A_0402V-0.1UF,16V,10%,X7R,A A36096-030               C2T3            
CAP_A_0402V-0.1UF,16V,10%,X7R,A A36096-030               C2T4            
CAP_A_0402V-0.1UF,16V,10%,X7R,A A36096-030               C2T5            
CAP_A_0402V-0.1UF,16V,10%,X7R,A A36096-030               C2T8            
CAP_A_0402V-0.1UF,16V,10%,X7R,A A36096-030               C2T12           
CAP_A_0402V-0.1UF,16V,10%,X7R,A A36096-030               C2T15           
CAP_A_0402V-0.1UF,16V,10%,X7R,A A36096-030               C2T16           
CAP_A_0402V-0.1UF,16V,10%,X7R,A A36096-030               C2T17           
CAP_A_0402V-0.1UF,16V,10%,X7R,A A36096-030               C2T21           
CAP_A_0402V-0.1UF,16V,10%,X7R,A A36096-030               C2T24           
CAP_A_0402V-0.1UF,16V,10%,X7R,A A36096-030               C2T25           
CAP_A_0402V-0.1UF,16V,10%,X7R,A A36096-030               C2T26           
CAP_A_0402V-0.1UF,16V,10%,X7R,A A36096-030               C2T29           
CAP_A_0402V-0.1UF,16V,10%,X7R,A A36096-030               C2T30           
CAP_A_0402V-0.1UF,16V,10%,X7R,A A36096-030               C2T32           
CAP_A_0402V-0.1UF,16V,10%,X7R,A A36096-030               C2T34           
CAP_A_0402V-0.1UF,16V,10%,X7R,A A36096-030               C2T35           
CAP_A_0402V-0.1UF,16V,10%,X7R,A A36096-030               C2T36           
CAP_A_0402V-0.1UF,16V,10%,X7R,A A36096-030               C2U19           
CAP_A_0402V-0.1UF,16V,10%,X7R,A A36096-030               C2U20           
CAP_A_0402V-0.1UF,16V,10%,X7R,A A36096-030               C2U21           
CAP_A_0402V-0.1UF,16V,10%,X7R,A A36096-030               C2U22           
CAP_A_0402V-0.1UF,16V,10%,X7R,A A36096-030               C2U23           
CAP_A_0402V-0.1UF,16V,10%,X7R,A A36096-030               C2U24           
CAP_A_0402V-0.1UF,16V,10%,X7R,A A36096-030               C2U25           
CAP_A_0402V-0.1UF,16V,10%,X7R,A A36096-030               C2U27           
CAP_A_0402V-0.1UF,16V,10%,X7R,A A36096-030               C2U28           
CAP_A_0402V-0.1UF,16V,10%,X7R,A A36096-030               C3B4            
CAP_A_0402V-0.1UF,16V,10%,X7R,A A36096-030               C3B5            
CAP_A_0402V-0.1UF,16V,10%,X7R,A A36096-030               C3F2            
CAP_A_0402V-0.1UF,16V,10%,X7R,A A36096-030               C3L31           
CAP_A_0402V-0.1UF,16V,10%,X7R,A A36096-030               C3N29           
CAP_A_0402V-0.1UF,16V,10%,X7R,A A36096-030               C3P5            
CAP_A_0402V-0.1UF,16V,10%,X7R,A A36096-030               C3P7            
CAP_A_0402V-0.1UF,16V,10%,X7R,A A36096-030               C3P43           
CAP_A_0402V-0.1UF,16V,10%,X7R,A A36096-030               C3P44           
CAP_A_0402V-0.1UF,16V,10%,X7R,A A36096-030               C3P46           
CAP_A_0402V-0.1UF,16V,10%,X7R,A A36096-030               C3P47           
CAP_A_0402V-0.1UF,16V,10%,X7R,A A36096-030               C3P48           
CAP_A_0402V-0.1UF,16V,10%,X7R,A A36096-030               C3P49           
CAP_A_0402V-0.1UF,16V,10%,X7R,A A36096-030               C3P51           
CAP_A_0402V-0.1UF,16V,10%,X7R,A A36096-030               C3P52           
CAP_A_0402V-0.1UF,16V,10%,X7R,A A36096-030               C3R1            
CAP_A_0402V-0.1UF,16V,10%,X7R,A A36096-030               C3R2            
CAP_A_0402V-0.1UF,16V,10%,X7R,A A36096-030               C3R3            
CAP_A_0402V-0.1UF,16V,10%,X7R,A A36096-030               C3U10           
CAP_A_0402V-0.1UF,16V,10%,X7R,A A36096-030               C4A20           
CAP_A_0402V-0.1UF,16V,10%,X7R,A A36096-030               C4C10           
CAP_A_0402V-0.1UF,16V,10%,X7R,A A36096-030               C4C19           
CAP_A_0402V-0.1UF,16V,10%,X7R,A A36096-030               C4D11           
CAP_A_0402V-0.1UF,16V,10%,X7R,A A36096-030               C4D19           
CAP_A_0402V-0.1UF,16V,10%,X7R,A A36096-030               C4D22           
CAP_A_0402V-0.1UF,16V,10%,X7R,A A36096-030               C4D24           
CAP_A_0402V-0.1UF,16V,10%,X7R,A A36096-030               C4D26           
CAP_A_0402V-0.1UF,16V,10%,X7R,A A36096-030               C4D32           
CAP_A_0402V-0.1UF,16V,10%,X7R,A A36096-030               C4D35           
CAP_A_0402V-0.1UF,16V,10%,X7R,A A36096-030               C4D38           
CAP_A_0402V-0.1UF,16V,10%,X7R,A A36096-030               C4D49           
CAP_A_0402V-0.1UF,16V,10%,X7R,A A36096-030               C4E13           
CAP_A_0402V-0.1UF,16V,10%,X7R,A A36096-030               C4E20           
CAP_A_0402V-0.1UF,16V,10%,X7R,A A36096-030               C4G22           
CAP_A_0402V-0.1UF,16V,10%,X7R,A A36096-030               C4G25           
CAP_A_0402V-0.1UF,16V,10%,X7R,A A36096-030               C4R2            
CAP_A_0402V-0.1UF,16V,10%,X7R,A A36096-030               C6F1            
CAP_A_0402V-0.1UF,16V,10%,X7R,A A36096-030               C6F2            
CAP_A_0402V-0.1UF,16V,10%,X7R,A A36096-030               C6F3            
CAP_A_0402V-0.1UF,16V,10%,X7R,A A36096-030               C6M6            
CAP_A_0402V-0.1UF,16V,10%,X7R,A A36096-030               C6P4            
CAP_A_0402V-0.1UF,16V,10%,X7R,A A36096-030               C6P5            
CAP_A_0402V-0.1UF,16V,10%,X7R,A A36096-030               C6P6            
CAP_A_0402V-0.1UF,16V,10%,X7R,A A36096-030               C6P9            
CAP_A_0402V-0.1UF,16V,10%,X7R,A A36096-030               C6P10           
CAP_A_0402V-0.1UF,16V,10%,X7R,A A36096-030               C6P11           
CAP_A_0402V-0.1UF,16V,10%,X7R,A A36096-030               C6P12           
CAP_A_0402V-0.1UF,16V,10%,X7R,A A36096-030               C6U5            
CAP_A_0402V-0.1UF,16V,10%,X7R,A A36096-030               C7A5            
CAP_A_0402V-0.1UF,16V,10%,X7R,A A36096-030               C7A20           
CAP_A_0402V-0.1UF,16V,10%,X7R,A A36096-030               C7A38           
CAP_A_0402V-0.1UF,16V,10%,X7R,A A36096-030               C7A39           
CAP_A_0402V-0.1UF,16V,10%,X7R,A A36096-030               C7A40           
CAP_A_0402V-0.1UF,16V,10%,X7R,A A36096-030               C7B2            
CAP_A_0402V-0.1UF,16V,10%,X7R,A A36096-030               C7B6            
CAP_A_0402V-0.1UF,16V,10%,X7R,A A36096-030               C7C11           
CAP_A_0402V-0.1UF,16V,10%,X7R,A A36096-030               C7D1            
CAP_A_0402V-0.1UF,16V,10%,X7R,A A36096-030               C7D5            
CAP_A_0402V-0.1UF,16V,10%,X7R,A A36096-030               C7E1            
CAP_A_0402V-0.1UF,16V,10%,X7R,A A36096-030               C7E2            
CAP_A_0402V-0.1UF,16V,10%,X7R,A A36096-030               C7E3            
CAP_A_0402V-0.1UF,16V,10%,X7R,A A36096-030               C7E4            
CAP_A_0402V-0.1UF,16V,10%,X7R,A A36096-030               C7E5            
CAP_A_0402V-0.1UF,16V,10%,X7R,A A36096-030               C7E9            
CAP_A_0402V-0.1UF,16V,10%,X7R,A A36096-030               C7F6            
CAP_A_0402V-0.1UF,16V,10%,X7R,A A36096-030               C7F15           
CAP_A_0402V-0.1UF,16V,10%,X7R,A A36096-030               C7F17           
CAP_A_0402V-0.1UF,16V,10%,X7R,A A36096-030               C7G29           
CAP_A_0402V-0.1UF,16V,10%,X7R,A A36096-030               C7G36           
CAP_A_0402V-0.1UF,16V,10%,X7R,A A36096-030               C8A8            
CAP_A_0402V-0.1UF,16V,10%,X7R,A A36096-030               C8B5            
CAP_A_0402V-0.1UF,16V,10%,X7R,A A36096-030               C8B7            
CAP_A_0402V-0.1UF,16V,10%,X7R,A A36096-030               C8B8            
CAP_A_0402V-0.1UF,16V,10%,X7R,A A36096-030               C8C8            
CAP_A_0402V-0.1UF,16V,10%,X7R,A A36096-030               C8C9            
CAP_A_0402V-0.1UF,16V,10%,X7R,A A36096-030               C8C10           
CAP_A_0402V-0.1UF,16V,10%,X7R,A A36096-030               C8C11           
CAP_A_0402V-0.1UF,16V,10%,X7R,A A36096-030               C8C12           
CAP_A_0402V-0.1UF,16V,10%,X7R,A A36096-030               C8C13           
CAP_A_0402V-0.1UF,16V,10%,X7R,A A36096-030               C8C14           
CAP_A_0402V-0.1UF,16V,10%,X7R,A A36096-030               C8C15           
CAP_A_0402V-0.1UF,16V,10%,X7R,A A36096-030               C8D1            
CAP_A_0402V-0.1UF,16V,10%,X7R,A A36096-030               C8D2            
CAP_A_0402V-0.1UF,16V,10%,X7R,A A36096-030               C8D4            
CAP_A_0402V-0.1UF,16V,10%,X7R,A A36096-030               C8E1            
CAP_A_0402V-0.1UF,16V,10%,X7R,A A36096-030               C8E2            
CAP_A_0402V-0.1UF,16V,10%,X7R,A A36096-030               C8E3            
CAP_A_0402V-0.1UF,16V,10%,X7R,A A36096-030               C8E5            
CAP_A_0402V-0.1UF,16V,10%,X7R,A A36096-030               C8E8            
CAP_A_0402V-0.1UF,16V,10%,X7R,A A36096-030               C8E18           
CAP_A_0402V-0.1UF,16V,10%,X7R,A A36096-030               C8E19           
CAP_A_0402V-0.1UF,16V,10%,X7R,A A36096-030               C8F16           
CAP_A_0402V-0.1UF,16V,10%,X7R,A A36096-030               C8F17           
CAP_A_0402V-0.1UF,16V,10%,X7R,A A36096-030               C9A1            
CAP_A_0402V-0.1UF,16V,10%,X7R,A A36096-030               C9A2            
CAP_A_0402V-0.1UF,16V,10%,X7R,A A36096-030               C9A3            
CAP_A_0402V-0.1UF,16V,10%,X7R,A A36096-030               C9A4            
CAP_A_0402V-0.1UF,16V,10%,X7R,A A36096-030               C9A5            
CAP_A_0402V-0.1UF,16V,10%,X7R,A A36096-030               C9B7            
CAP_A_0402V-0.1UF,16V,10%,X7R,A A36096-030               C9B10           
CAP_A_0402V-0.1UF,16V,10%,X7R,A A36096-030               C9E4            
CAP_A_0402V-0.1UF,16V,10%,X7R,A A36096-030               C9E5            
CAP_A_0402V-0.1UF,16V,10%,X7R,A A36096-030               C9F5            
CAP_A_0402V-0.1UF,16V,10%,X7R,A A36096-030               C9F11           
CAP_A_0402V-0.1UF,16V,10%,X7R,A A36096-030               C9F14           
CAP_A_0402V-0.1UF,16V,10%,X7R,A A36096-030               C9F19           
CAP_A_0402V-0.1UF,16V,10%,X7R,A A36096-030               C9F23           
CAP_A_0402V-0.1UF,16V,10%,X7R,A A36096-030               C9G4            
CAP_A_0402V-0.1UF,16V,10%,X7R,A A36096-030               C9G6            
CAP_A_0402V-0.1UF,16V,10%,X7R,A A36096-030               C9G7            
CAP_A_0402V-0.1UF,16V,10%,X7R,A A36096-030               C9G19           
CAP_A_0402V-0.1UF,16V,10%,X7R,A A36096-030               C9M5            
CAP_A_0402V-0.1UF,16V,10%,X7R,A A36096-030               C9M6            
CAP_A_0402V-0.1UF,16V,10%,X7R,A A36096-030               C9M7            
CAP_A_0402V-0.1UF,16V,10%,X7R,A A36096-030               C9M8            
CAP_A_0402V-0.1UF,16V,10%,X7R,A A36096-030               C9M9            
CAP_A_0402V-0.1UF,16V,10%,X7R,A A36096-030               C9M11           
CAP_A_0402V-0.1UF,16V,10%,X7R,A A36096-030               C9P6            
CAP_A_0402V-0.1UF,16V,10%,X7R,A A36096-030               C9P11           
CAP_A_0402V-0.1UF,16V,10%,X7R,A A36096-030               C9P15           
CAP_A_0402V-0.1UF,16V,10%,X7R,A A36096-030               C9R6            
CAP_A_0402V-0.1UF,16V,10%,X7R,A A36096-030               C9R12           
CAP_A_0402V-0.1UF,16V,10%,X7R,A A36096-030               C9R13           
CAP_A_0402V-0.1UF,16V,10%,X7R,A A36096-030               C9R14           
CAP_A_0402V-0.1UF,16V,10%,X7R,A A36096-030               C9U12           
CAP_A_0402V-0.1UF,16V,10%,X7R,A A36096-030               CTI1            
CAP_A_0402V-0.1UF,16V,10%,X7R,A A36096-030               CTI6            
CAP_A_0402V-0.1UF,16V,10%,X7R,A A36096-030               CTI7            
CAP_A_0402V-0.1UF,16V,10%,X7R,A A36096-030               CTI12           
CAP_A_0402V-0.1UF,16V,10%,X7R,A A36096-030               CTI13           
CAP_A_0402V-0.1UF,16V,10%,X7R,A A36096-030               CTI16           
CAP_A_0402V-0.1UF,16V,10%,X7R,A A36096-030               CTI21           
CAP_A_0402V-0.1UF,16V,10%,X7R,A A36096-030               CTI24           
CAP_A_0402V-0.1UF,16V,10%,X7R,A A36096-030               CTI25           
CAP_A_0402V-0.1UF,16V,10%,X7R,A A36096-030               CTI30           
CAP_A_0402V-0.1UF,16V,10%,X7R,A A36096-030               CTI31           
CAP_A_0402V-0.1UF,16V,10%,X7R,A A36096-030               CTI36           
CAP_A_0402V-0.1UF,16V,10%,X7R,A A36096-030               CTI39           
CAP_A_0402V-0.1UF,16V,10%,X7R,A A36096-030               CTI40           
CAP_A_0402V-0.1UF,16V,10%,X7R,A A36096-030               CTI45           
CAP_A_0402V-0.1UF,16V,10%,X7R,A A36096-030               CTI46           
CAP_A_0402V-0.1UF,16V,10%,X7R,A A36096-030               CTI51           
CAP_A_0402V-0.1UF,16V,10%,X7R,A A36096-030               CTI52           
CAP_A_0402V-0.1UF,16V,10%,X7R,A A36096-030               CTI57           
CAP_A_0402V-0.1UF,16V,10%,X7R,A A36096-030               CTI60           
CAP_A_0402V-0.1UF,16V,10%,X7R,A A36096-030               CTI63           
CAP_A_0402V-0.1UF,16V,10%,X7R,A A36096-030               CTI66           
CAP_A_0402V-0.1UF,16V,10%,X7R,A A36096-030               CTI67           
CAP_A_0402V-0.1UF,16V,10%,X7R,A A36096-030               CTI70           

----------------

CAP_A_0402V-1.0UF,6.3V,10%,EMPA D97712-004               C1T18           
CAP_A_0402V-1.0UF,6.3V,10%,EMPA D97712-004               C8F9            

----------------

CAP_A_0402V-1.0UF,6.3V,10%,X6SA D97712-004               C1A2            
CAP_A_0402V-1.0UF,6.3V,10%,X6SA D97712-004               C1A11           
CAP_A_0402V-1.0UF,6.3V,10%,X6SA D97712-004               C1B3            
CAP_A_0402V-1.0UF,6.3V,10%,X6SA D97712-004               C1B6            
CAP_A_0402V-1.0UF,6.3V,10%,X6SA D97712-004               C1C3            
CAP_A_0402V-1.0UF,6.3V,10%,X6SA D97712-004               C1C7            
CAP_A_0402V-1.0UF,6.3V,10%,X6SA D97712-004               C1C13           
CAP_A_0402V-1.0UF,6.3V,10%,X6SA D97712-004               C1C18           
CAP_A_0402V-1.0UF,6.3V,10%,X6SA D97712-004               C1D5            
CAP_A_0402V-1.0UF,6.3V,10%,X6SA D97712-004               C1D15           
CAP_A_0402V-1.0UF,6.3V,10%,X6SA D97712-004               C1E6            
CAP_A_0402V-1.0UF,6.3V,10%,X6SA D97712-004               C1E23           
CAP_A_0402V-1.0UF,6.3V,10%,X6SA D97712-004               C1F21           
CAP_A_0402V-1.0UF,6.3V,10%,X6SA D97712-004               C1G4            
CAP_A_0402V-1.0UF,6.3V,10%,X6SA D97712-004               C1G23           
CAP_A_0402V-1.0UF,6.3V,10%,X6SA D97712-004               C1G27           
CAP_A_0402V-1.0UF,6.3V,10%,X6SA D97712-004               C1L5            
CAP_A_0402V-1.0UF,6.3V,10%,X6SA D97712-004               C1L10           
CAP_A_0402V-1.0UF,6.3V,10%,X6SA D97712-004               C1L18           
CAP_A_0402V-1.0UF,6.3V,10%,X6SA D97712-004               C1M3            
CAP_A_0402V-1.0UF,6.3V,10%,X6SA D97712-004               C1M21           
CAP_A_0402V-1.0UF,6.3V,10%,X6SA D97712-004               C1M25           
CAP_A_0402V-1.0UF,6.3V,10%,X6SA D97712-004               C1M32           
CAP_A_0402V-1.0UF,6.3V,10%,X6SA D97712-004               C1M37           
CAP_A_0402V-1.0UF,6.3V,10%,X6SA D97712-004               C1T12           
CAP_A_0402V-1.0UF,6.3V,10%,X6SA D97712-004               C1T19           
CAP_A_0402V-1.0UF,6.3V,10%,X6SA D97712-004               C1T21           
CAP_A_0402V-1.0UF,6.3V,10%,X6SA D97712-004               C1T28           
CAP_A_0402V-1.0UF,6.3V,10%,X6SA D97712-004               C1T31           
CAP_A_0402V-1.0UF,6.3V,10%,X6SA D97712-004               C1T32           
CAP_A_0402V-1.0UF,6.3V,10%,X6SA D97712-004               C1T35           
CAP_A_0402V-1.0UF,6.3V,10%,X6SA D97712-004               C1T46           
CAP_A_0402V-1.0UF,6.3V,10%,X6SA D97712-004               C1T49           
CAP_A_0402V-1.0UF,6.3V,10%,X6SA D97712-004               C1T51           
CAP_A_0402V-1.0UF,6.3V,10%,X6SA D97712-004               C1T55           
CAP_A_0402V-1.0UF,6.3V,10%,X6SA D97712-004               C1U6            
CAP_A_0402V-1.0UF,6.3V,10%,X6SA D97712-004               C1U7            
CAP_A_0402V-1.0UF,6.3V,10%,X6SA D97712-004               C1U8            
CAP_A_0402V-1.0UF,6.3V,10%,X6SA D97712-004               C1U18           
CAP_A_0402V-1.0UF,6.3V,10%,X6SA D97712-004               C2L8            
CAP_A_0402V-1.0UF,6.3V,10%,X6SA D97712-004               C2M6            
CAP_A_0402V-1.0UF,6.3V,10%,X6SA D97712-004               C2M7            
CAP_A_0402V-1.0UF,6.3V,10%,X6SA D97712-004               C2M8            
CAP_A_0402V-1.0UF,6.3V,10%,X6SA D97712-004               C2M9            
CAP_A_0402V-1.0UF,6.3V,10%,X6SA D97712-004               C2M16           
CAP_A_0402V-1.0UF,6.3V,10%,X6SA D97712-004               C2M18           
CAP_A_0402V-1.0UF,6.3V,10%,X6SA D97712-004               C2M19           
CAP_A_0402V-1.0UF,6.3V,10%,X6SA D97712-004               C2M20           
CAP_A_0402V-1.0UF,6.3V,10%,X6SA D97712-004               C2M21           
CAP_A_0402V-1.0UF,6.3V,10%,X6SA D97712-004               C2M22           
CAP_A_0402V-1.0UF,6.3V,10%,X6SA D97712-004               C2M25           
CAP_A_0402V-1.0UF,6.3V,10%,X6SA D97712-004               C2N2            
CAP_A_0402V-1.0UF,6.3V,10%,X6SA D97712-004               C2N3            
CAP_A_0402V-1.0UF,6.3V,10%,X6SA D97712-004               C2N4            
CAP_A_0402V-1.0UF,6.3V,10%,X6SA D97712-004               C2N5            
CAP_A_0402V-1.0UF,6.3V,10%,X6SA D97712-004               C2N7            
CAP_A_0402V-1.0UF,6.3V,10%,X6SA D97712-004               C2N8            
CAP_A_0402V-1.0UF,6.3V,10%,X6SA D97712-004               C2N9            
CAP_A_0402V-1.0UF,6.3V,10%,X6SA D97712-004               C2N11           
CAP_A_0402V-1.0UF,6.3V,10%,X6SA D97712-004               C2N12           
CAP_A_0402V-1.0UF,6.3V,10%,X6SA D97712-004               C2N13           
CAP_A_0402V-1.0UF,6.3V,10%,X6SA D97712-004               C2N15           
CAP_A_0402V-1.0UF,6.3V,10%,X6SA D97712-004               C2N16           
CAP_A_0402V-1.0UF,6.3V,10%,X6SA D97712-004               C2N18           
CAP_A_0402V-1.0UF,6.3V,10%,X6SA D97712-004               C2N19           
CAP_A_0402V-1.0UF,6.3V,10%,X6SA D97712-004               C2N20           
CAP_A_0402V-1.0UF,6.3V,10%,X6SA D97712-004               C2N25           
CAP_A_0402V-1.0UF,6.3V,10%,X6SA D97712-004               C2N26           
CAP_A_0402V-1.0UF,6.3V,10%,X6SA D97712-004               C2R12           
CAP_A_0402V-1.0UF,6.3V,10%,X6SA D97712-004               C2T19           
CAP_A_0402V-1.0UF,6.3V,10%,X6SA D97712-004               C2T28           
CAP_A_0402V-1.0UF,6.3V,10%,X6SA D97712-004               C2T31           
CAP_A_0402V-1.0UF,6.3V,10%,X6SA D97712-004               C2T33           
CAP_A_0402V-1.0UF,6.3V,10%,X6SA D97712-004               C2T38           
CAP_A_0402V-1.0UF,6.3V,10%,X6SA D97712-004               C2U26           
CAP_A_0402V-1.0UF,6.3V,10%,X6SA D97712-004               C3C1            
CAP_A_0402V-1.0UF,6.3V,10%,X6SA D97712-004               C3C2            
CAP_A_0402V-1.0UF,6.3V,10%,X6SA D97712-004               C3L1            
CAP_A_0402V-1.0UF,6.3V,10%,X6SA D97712-004               C3L29           
CAP_A_0402V-1.0UF,6.3V,10%,X6SA D97712-004               C3M19           
CAP_A_0402V-1.0UF,6.3V,10%,X6SA D97712-004               C3M20           
CAP_A_0402V-1.0UF,6.3V,10%,X6SA D97712-004               C3M21           
CAP_A_0402V-1.0UF,6.3V,10%,X6SA D97712-004               C3M22           
CAP_A_0402V-1.0UF,6.3V,10%,X6SA D97712-004               C3M27           
CAP_A_0402V-1.0UF,6.3V,10%,X6SA D97712-004               C3M29           
CAP_A_0402V-1.0UF,6.3V,10%,X6SA D97712-004               C3M30           
CAP_A_0402V-1.0UF,6.3V,10%,X6SA D97712-004               C3M31           
CAP_A_0402V-1.0UF,6.3V,10%,X6SA D97712-004               C3M38           
CAP_A_0402V-1.0UF,6.3V,10%,X6SA D97712-004               C3M39           
CAP_A_0402V-1.0UF,6.3V,10%,X6SA D97712-004               C3M42           
CAP_A_0402V-1.0UF,6.3V,10%,X6SA D97712-004               C3M43           
CAP_A_0402V-1.0UF,6.3V,10%,X6SA D97712-004               C3M46           
CAP_A_0402V-1.0UF,6.3V,10%,X6SA D97712-004               C3N1            
CAP_A_0402V-1.0UF,6.3V,10%,X6SA D97712-004               C3N2            
CAP_A_0402V-1.0UF,6.3V,10%,X6SA D97712-004               C3N3            
CAP_A_0402V-1.0UF,6.3V,10%,X6SA D97712-004               C3N4            
CAP_A_0402V-1.0UF,6.3V,10%,X6SA D97712-004               C3N5            
CAP_A_0402V-1.0UF,6.3V,10%,X6SA D97712-004               C3N6            
CAP_A_0402V-1.0UF,6.3V,10%,X6SA D97712-004               C3N7            
CAP_A_0402V-1.0UF,6.3V,10%,X6SA D97712-004               C3N15           
CAP_A_0402V-1.0UF,6.3V,10%,X6SA D97712-004               C3N16           
CAP_A_0402V-1.0UF,6.3V,10%,X6SA D97712-004               C3N17           
CAP_A_0402V-1.0UF,6.3V,10%,X6SA D97712-004               C3N18           
CAP_A_0402V-1.0UF,6.3V,10%,X6SA D97712-004               C3N19           
CAP_A_0402V-1.0UF,6.3V,10%,X6SA D97712-004               C3N20           
CAP_A_0402V-1.0UF,6.3V,10%,X6SA D97712-004               C3N21           
CAP_A_0402V-1.0UF,6.3V,10%,X6SA D97712-004               C3N22           
CAP_A_0402V-1.0UF,6.3V,10%,X6SA D97712-004               C3N23           
CAP_A_0402V-1.0UF,6.3V,10%,X6SA D97712-004               C3N25           
CAP_A_0402V-1.0UF,6.3V,10%,X6SA D97712-004               C3N32           
CAP_A_0402V-1.0UF,6.3V,10%,X6SA D97712-004               C3N40           
CAP_A_0402V-1.0UF,6.3V,10%,X6SA D97712-004               C3P3            
CAP_A_0402V-1.0UF,6.3V,10%,X6SA D97712-004               C3P4            
CAP_A_0402V-1.0UF,6.3V,10%,X6SA D97712-004               C3P42           
CAP_A_0402V-1.0UF,6.3V,10%,X6SA D97712-004               C3T4            
CAP_A_0402V-1.0UF,6.3V,10%,X6SA D97712-004               C4C3            
CAP_A_0402V-1.0UF,6.3V,10%,X6SA D97712-004               C4C4            
CAP_A_0402V-1.0UF,6.3V,10%,X6SA D97712-004               C4C14           
CAP_A_0402V-1.0UF,6.3V,10%,X6SA D97712-004               C4D6            
CAP_A_0402V-1.0UF,6.3V,10%,X6SA D97712-004               C4D14           
CAP_A_0402V-1.0UF,6.3V,10%,X6SA D97712-004               C4D15           
CAP_A_0402V-1.0UF,6.3V,10%,X6SA D97712-004               C4D23           
CAP_A_0402V-1.0UF,6.3V,10%,X6SA D97712-004               C4D25           
CAP_A_0402V-1.0UF,6.3V,10%,X6SA D97712-004               C4D27           
CAP_A_0402V-1.0UF,6.3V,10%,X6SA D97712-004               C4D31           
CAP_A_0402V-1.0UF,6.3V,10%,X6SA D97712-004               C4D36           
CAP_A_0402V-1.0UF,6.3V,10%,X6SA D97712-004               C4E6            
CAP_A_0402V-1.0UF,6.3V,10%,X6SA D97712-004               C4E25           
CAP_A_0402V-1.0UF,6.3V,10%,X6SA D97712-004               C4E28           
CAP_A_0402V-1.0UF,6.3V,10%,X6SA D97712-004               C4F1            
CAP_A_0402V-1.0UF,6.3V,10%,X6SA D97712-004               C4F3            
CAP_A_0402V-1.0UF,6.3V,10%,X6SA D97712-004               C4T1            
CAP_A_0402V-1.0UF,6.3V,10%,X6SA D97712-004               C4T2            
CAP_A_0402V-1.0UF,6.3V,10%,X6SA D97712-004               C7A18           
CAP_A_0402V-1.0UF,6.3V,10%,X6SA D97712-004               C7A26           
CAP_A_0402V-1.0UF,6.3V,10%,X6SA D97712-004               C7A37           
CAP_A_0402V-1.0UF,6.3V,10%,X6SA D97712-004               C7B1            
CAP_A_0402V-1.0UF,6.3V,10%,X6SA D97712-004               C7C19           
CAP_A_0402V-1.0UF,6.3V,10%,X6SA D97712-004               C7C20           
CAP_A_0402V-1.0UF,6.3V,10%,X6SA D97712-004               C7F2            
CAP_A_0402V-1.0UF,6.3V,10%,X6SA D97712-004               C7F16           
CAP_A_0402V-1.0UF,6.3V,10%,X6SA D97712-004               C7F18           
CAP_A_0402V-1.0UF,6.3V,10%,X6SA D97712-004               C7G35           
CAP_A_0402V-1.0UF,6.3V,10%,X6SA D97712-004               C7G42           
CAP_A_0402V-1.0UF,6.3V,10%,X6SA D97712-004               C8A7            
CAP_A_0402V-1.0UF,6.3V,10%,X6SA D97712-004               C8F4            
CAP_A_0402V-1.0UF,6.3V,10%,X6SA D97712-004               C9A6            
CAP_A_0402V-1.0UF,6.3V,10%,X6SA D97712-004               C9B9            
CAP_A_0402V-1.0UF,6.3V,10%,X6SA D97712-004               C9F12           

----------------

CAP_A_0603V-22.0UF,4V,20%,EMPTA E15431-004               C9E1            
CAP_A_0603V-22.0UF,4V,20%,EMPTA E15431-004               C9E12           

----------------

CAP_A_0603V-22.0UF,4V,20%,X6S,A E15431-004               C1C19           
CAP_A_0603V-22.0UF,4V,20%,X6S,A E15431-004               C1D3            
CAP_A_0603V-22.0UF,4V,20%,X6S,A E15431-004               C1D14           
CAP_A_0603V-22.0UF,4V,20%,X6S,A E15431-004               C1D24           
CAP_A_0603V-22.0UF,4V,20%,X6S,A E15431-004               C1E3            
CAP_A_0603V-22.0UF,4V,20%,X6S,A E15431-004               C1E9            
CAP_A_0603V-22.0UF,4V,20%,X6S,A E15431-004               C2A1            
CAP_A_0603V-22.0UF,4V,20%,X6S,A E15431-004               C2A2            
CAP_A_0603V-22.0UF,4V,20%,X6S,A E15431-004               C2A3            
CAP_A_0603V-22.0UF,4V,20%,X6S,A E15431-004               C2A4            
CAP_A_0603V-22.0UF,4V,20%,X6S,A E15431-004               C2A6            
CAP_A_0603V-22.0UF,4V,20%,X6S,A E15431-004               C2A7            
CAP_A_0603V-22.0UF,4V,20%,X6S,A E15431-004               C2A9            
CAP_A_0603V-22.0UF,4V,20%,X6S,A E15431-004               C2A10           
CAP_A_0603V-22.0UF,4V,20%,X6S,A E15431-004               C2A11           
CAP_A_0603V-22.0UF,4V,20%,X6S,A E15431-004               C2A12           
CAP_A_0603V-22.0UF,4V,20%,X6S,A E15431-004               C2A13           
CAP_A_0603V-22.0UF,4V,20%,X6S,A E15431-004               C2A14           
CAP_A_0603V-22.0UF,4V,20%,X6S,A E15431-004               C2A15           
CAP_A_0603V-22.0UF,4V,20%,X6S,A E15431-004               C2D1            
CAP_A_0603V-22.0UF,4V,20%,X6S,A E15431-004               C2D2            
CAP_A_0603V-22.0UF,4V,20%,X6S,A E15431-004               C2D3            
CAP_A_0603V-22.0UF,4V,20%,X6S,A E15431-004               C2D12           
CAP_A_0603V-22.0UF,4V,20%,X6S,A E15431-004               C2D13           
CAP_A_0603V-22.0UF,4V,20%,X6S,A E15431-004               C2D14           
CAP_A_0603V-22.0UF,4V,20%,X6S,A E15431-004               C2D15           
CAP_A_0603V-22.0UF,4V,20%,X6S,A E15431-004               C2D16           
CAP_A_0603V-22.0UF,4V,20%,X6S,A E15431-004               C2D17           
CAP_A_0603V-22.0UF,4V,20%,X6S,A E15431-004               C2D18           
CAP_A_0603V-22.0UF,4V,20%,X6S,A E15431-004               C2D19           
CAP_A_0603V-22.0UF,4V,20%,X6S,A E15431-004               C2D20           
CAP_A_0603V-22.0UF,4V,20%,X6S,A E15431-004               C2D21           
CAP_A_0603V-22.0UF,4V,20%,X6S,A E15431-004               C2D22           
CAP_A_0603V-22.0UF,4V,20%,X6S,A E15431-004               C2D23           
CAP_A_0603V-22.0UF,4V,20%,X6S,A E15431-004               C2D24           
CAP_A_0603V-22.0UF,4V,20%,X6S,A E15431-004               C2D25           
CAP_A_0603V-22.0UF,4V,20%,X6S,A E15431-004               C2D26           
CAP_A_0603V-22.0UF,4V,20%,X6S,A E15431-004               C2D27           
CAP_A_0603V-22.0UF,4V,20%,X6S,A E15431-004               C2D28           
CAP_A_0603V-22.0UF,4V,20%,X6S,A E15431-004               C2D29           
CAP_A_0603V-22.0UF,4V,20%,X6S,A E15431-004               C2D30           
CAP_A_0603V-22.0UF,4V,20%,X6S,A E15431-004               C2D31           
CAP_A_0603V-22.0UF,4V,20%,X6S,A E15431-004               C2D32           
CAP_A_0603V-22.0UF,4V,20%,X6S,A E15431-004               C2D33           
CAP_A_0603V-22.0UF,4V,20%,X6S,A E15431-004               C2D34           
CAP_A_0603V-22.0UF,4V,20%,X6S,A E15431-004               C2D35           
CAP_A_0603V-22.0UF,4V,20%,X6S,A E15431-004               C2D36           
CAP_A_0603V-22.0UF,4V,20%,X6S,A E15431-004               C2D37           
CAP_A_0603V-22.0UF,4V,20%,X6S,A E15431-004               C2D38           
CAP_A_0603V-22.0UF,4V,20%,X6S,A E15431-004               C2D39           
CAP_A_0603V-22.0UF,4V,20%,X6S,A E15431-004               C2D40           
CAP_A_0603V-22.0UF,4V,20%,X6S,A E15431-004               C2D45           
CAP_A_0603V-22.0UF,4V,20%,X6S,A E15431-004               C2D46           
CAP_A_0603V-22.0UF,4V,20%,X6S,A E15431-004               C2D47           
CAP_A_0603V-22.0UF,4V,20%,X6S,A E15431-004               C2G1            
CAP_A_0603V-22.0UF,4V,20%,X6S,A E15431-004               C2G2            
CAP_A_0603V-22.0UF,4V,20%,X6S,A E15431-004               C2G3            
CAP_A_0603V-22.0UF,4V,20%,X6S,A E15431-004               C2G4            
CAP_A_0603V-22.0UF,4V,20%,X6S,A E15431-004               C2G5            
CAP_A_0603V-22.0UF,4V,20%,X6S,A E15431-004               C2G6            
CAP_A_0603V-22.0UF,4V,20%,X6S,A E15431-004               C2G9            
CAP_A_0603V-22.0UF,4V,20%,X6S,A E15431-004               C2G10           
CAP_A_0603V-22.0UF,4V,20%,X6S,A E15431-004               C2G11           
CAP_A_0603V-22.0UF,4V,20%,X6S,A E15431-004               C2G12           
CAP_A_0603V-22.0UF,4V,20%,X6S,A E15431-004               C2G13           
CAP_A_0603V-22.0UF,4V,20%,X6S,A E15431-004               C2G14           
CAP_A_0603V-22.0UF,4V,20%,X6S,A E15431-004               C2M1            
CAP_A_0603V-22.0UF,4V,20%,X6S,A E15431-004               C2M2            
CAP_A_0603V-22.0UF,4V,20%,X6S,A E15431-004               C2M12           
CAP_A_0603V-22.0UF,4V,20%,X6S,A E15431-004               C2M13           
CAP_A_0603V-22.0UF,4V,20%,X6S,A E15431-004               C2N10           
CAP_A_0603V-22.0UF,4V,20%,X6S,A E15431-004               C3A1            
CAP_A_0603V-22.0UF,4V,20%,X6S,A E15431-004               C3A2            
CAP_A_0603V-22.0UF,4V,20%,X6S,A E15431-004               C3A5            
CAP_A_0603V-22.0UF,4V,20%,X6S,A E15431-004               C3A6            
CAP_A_0603V-22.0UF,4V,20%,X6S,A E15431-004               C3D1            
CAP_A_0603V-22.0UF,4V,20%,X6S,A E15431-004               C3D2            
CAP_A_0603V-22.0UF,4V,20%,X6S,A E15431-004               C3D4            
CAP_A_0603V-22.0UF,4V,20%,X6S,A E15431-004               C3D5            
CAP_A_0603V-22.0UF,4V,20%,X6S,A E15431-004               C3D6            
CAP_A_0603V-22.0UF,4V,20%,X6S,A E15431-004               C3D7            
CAP_A_0603V-22.0UF,4V,20%,X6S,A E15431-004               C3D8            
CAP_A_0603V-22.0UF,4V,20%,X6S,A E15431-004               C3D9            
CAP_A_0603V-22.0UF,4V,20%,X6S,A E15431-004               C3D10           
CAP_A_0603V-22.0UF,4V,20%,X6S,A E15431-004               C3D11           
CAP_A_0603V-22.0UF,4V,20%,X6S,A E15431-004               C3D12           
CAP_A_0603V-22.0UF,4V,20%,X6S,A E15431-004               C3D13           
CAP_A_0603V-22.0UF,4V,20%,X6S,A E15431-004               C3D14           
CAP_A_0603V-22.0UF,4V,20%,X6S,A E15431-004               C3D15           
CAP_A_0603V-22.0UF,4V,20%,X6S,A E15431-004               C3D16           
CAP_A_0603V-22.0UF,4V,20%,X6S,A E15431-004               C3D17           
CAP_A_0603V-22.0UF,4V,20%,X6S,A E15431-004               C3D18           
CAP_A_0603V-22.0UF,4V,20%,X6S,A E15431-004               C3D19           
CAP_A_0603V-22.0UF,4V,20%,X6S,A E15431-004               C3D20           
CAP_A_0603V-22.0UF,4V,20%,X6S,A E15431-004               C3D21           
CAP_A_0603V-22.0UF,4V,20%,X6S,A E15431-004               C3D23           
CAP_A_0603V-22.0UF,4V,20%,X6S,A E15431-004               C3D24           
CAP_A_0603V-22.0UF,4V,20%,X6S,A E15431-004               C3D25           
CAP_A_0603V-22.0UF,4V,20%,X6S,A E15431-004               C3E1            
CAP_A_0603V-22.0UF,4V,20%,X6S,A E15431-004               C3G1            
CAP_A_0603V-22.0UF,4V,20%,X6S,A E15431-004               C3G2            
CAP_A_0603V-22.0UF,4V,20%,X6S,A E15431-004               C3G5            
CAP_A_0603V-22.0UF,4V,20%,X6S,A E15431-004               C3G6            
CAP_A_0603V-22.0UF,4V,20%,X6S,A E15431-004               C3L22           
CAP_A_0603V-22.0UF,4V,20%,X6S,A E15431-004               C3L23           
CAP_A_0603V-22.0UF,4V,20%,X6S,A E15431-004               C3L24           
CAP_A_0603V-22.0UF,4V,20%,X6S,A E15431-004               C3L25           
CAP_A_0603V-22.0UF,4V,20%,X6S,A E15431-004               C3L26           
CAP_A_0603V-22.0UF,4V,20%,X6S,A E15431-004               C3L27           
CAP_A_0603V-22.0UF,4V,20%,X6S,A E15431-004               C3M6            
CAP_A_0603V-22.0UF,4V,20%,X6S,A E15431-004               C3M7            
CAP_A_0603V-22.0UF,4V,20%,X6S,A E15431-004               C3N10           
CAP_A_0603V-22.0UF,4V,20%,X6S,A E15431-004               C3N11           
CAP_A_0603V-22.0UF,4V,20%,X6S,A E15431-004               C3N12           
CAP_A_0603V-22.0UF,4V,20%,X6S,A E15431-004               C3N24           
CAP_A_0603V-22.0UF,4V,20%,X6S,A E15431-004               C3N27           
CAP_A_0603V-22.0UF,4V,20%,X6S,A E15431-004               C3N28           
CAP_A_0603V-22.0UF,4V,20%,X6S,A E15431-004               C3N30           
CAP_A_0603V-22.0UF,4V,20%,X6S,A E15431-004               C3N31           
CAP_A_0603V-22.0UF,4V,20%,X6S,A E15431-004               C4C11           
CAP_A_0603V-22.0UF,4V,20%,X6S,A E15431-004               C4D4            
CAP_A_0603V-22.0UF,4V,20%,X6S,A E15431-004               C4D12           
CAP_A_0603V-22.0UF,4V,20%,X6S,A E15431-004               C4D34           
CAP_A_0603V-22.0UF,4V,20%,X6S,A E15431-004               C4E3            
CAP_A_0603V-22.0UF,4V,20%,X6S,A E15431-004               C4E11           
CAP_A_0603V-22.0UF,4V,20%,X6S,A E15431-004               C4M2            
CAP_A_0603V-22.0UF,4V,20%,X6S,A E15431-004               C4P6            
CAP_A_0603V-22.0UF,4V,20%,X6S,A E15431-004               C4P8            
CAP_A_0603V-22.0UF,4V,20%,X6S,A E15431-004               C5A1            
CAP_A_0603V-22.0UF,4V,20%,X6S,A E15431-004               C5A2            
CAP_A_0603V-22.0UF,4V,20%,X6S,A E15431-004               C5A3            
CAP_A_0603V-22.0UF,4V,20%,X6S,A E15431-004               C5A4            
CAP_A_0603V-22.0UF,4V,20%,X6S,A E15431-004               C5A6            
CAP_A_0603V-22.0UF,4V,20%,X6S,A E15431-004               C5A7            
CAP_A_0603V-22.0UF,4V,20%,X6S,A E15431-004               C5A8            
CAP_A_0603V-22.0UF,4V,20%,X6S,A E15431-004               C5A9            
CAP_A_0603V-22.0UF,4V,20%,X6S,A E15431-004               C5A11           
CAP_A_0603V-22.0UF,4V,20%,X6S,A E15431-004               C5A12           
CAP_A_0603V-22.0UF,4V,20%,X6S,A E15431-004               C5A13           
CAP_A_0603V-22.0UF,4V,20%,X6S,A E15431-004               C5A14           
CAP_A_0603V-22.0UF,4V,20%,X6S,A E15431-004               C5A15           
CAP_A_0603V-22.0UF,4V,20%,X6S,A E15431-004               C5A16           
CAP_A_0603V-22.0UF,4V,20%,X6S,A E15431-004               C5A17           
CAP_A_0603V-22.0UF,4V,20%,X6S,A E15431-004               C5A18           
CAP_A_0603V-22.0UF,4V,20%,X6S,A E15431-004               C5A19           
CAP_A_0603V-22.0UF,4V,20%,X6S,A E15431-004               C5D1            
CAP_A_0603V-22.0UF,4V,20%,X6S,A E15431-004               C5D2            
CAP_A_0603V-22.0UF,4V,20%,X6S,A E15431-004               C5D3            
CAP_A_0603V-22.0UF,4V,20%,X6S,A E15431-004               C5D4            
CAP_A_0603V-22.0UF,4V,20%,X6S,A E15431-004               C5D5            
CAP_A_0603V-22.0UF,4V,20%,X6S,A E15431-004               C5D14           
CAP_A_0603V-22.0UF,4V,20%,X6S,A E15431-004               C5D15           
CAP_A_0603V-22.0UF,4V,20%,X6S,A E15431-004               C5D16           
CAP_A_0603V-22.0UF,4V,20%,X6S,A E15431-004               C5D17           
CAP_A_0603V-22.0UF,4V,20%,X6S,A E15431-004               C5D18           
CAP_A_0603V-22.0UF,4V,20%,X6S,A E15431-004               C5D19           
CAP_A_0603V-22.0UF,4V,20%,X6S,A E15431-004               C5D20           
CAP_A_0603V-22.0UF,4V,20%,X6S,A E15431-004               C5D21           
CAP_A_0603V-22.0UF,4V,20%,X6S,A E15431-004               C5D22           
CAP_A_0603V-22.0UF,4V,20%,X6S,A E15431-004               C5D23           
CAP_A_0603V-22.0UF,4V,20%,X6S,A E15431-004               C5D24           
CAP_A_0603V-22.0UF,4V,20%,X6S,A E15431-004               C5D25           
CAP_A_0603V-22.0UF,4V,20%,X6S,A E15431-004               C5D26           
CAP_A_0603V-22.0UF,4V,20%,X6S,A E15431-004               C5D27           
CAP_A_0603V-22.0UF,4V,20%,X6S,A E15431-004               C5D28           
CAP_A_0603V-22.0UF,4V,20%,X6S,A E15431-004               C5D29           
CAP_A_0603V-22.0UF,4V,20%,X6S,A E15431-004               C5D30           
CAP_A_0603V-22.0UF,4V,20%,X6S,A E15431-004               C5D31           
CAP_A_0603V-22.0UF,4V,20%,X6S,A E15431-004               C5D32           
CAP_A_0603V-22.0UF,4V,20%,X6S,A E15431-004               C5D33           
CAP_A_0603V-22.0UF,4V,20%,X6S,A E15431-004               C5D34           
CAP_A_0603V-22.0UF,4V,20%,X6S,A E15431-004               C5D35           
CAP_A_0603V-22.0UF,4V,20%,X6S,A E15431-004               C5D36           
CAP_A_0603V-22.0UF,4V,20%,X6S,A E15431-004               C5D37           
CAP_A_0603V-22.0UF,4V,20%,X6S,A E15431-004               C5D38           
CAP_A_0603V-22.0UF,4V,20%,X6S,A E15431-004               C5D39           
CAP_A_0603V-22.0UF,4V,20%,X6S,A E15431-004               C5D40           
CAP_A_0603V-22.0UF,4V,20%,X6S,A E15431-004               C5D41           
CAP_A_0603V-22.0UF,4V,20%,X6S,A E15431-004               C5D42           
CAP_A_0603V-22.0UF,4V,20%,X6S,A E15431-004               C5D43           
CAP_A_0603V-22.0UF,4V,20%,X6S,A E15431-004               C5D44           
CAP_A_0603V-22.0UF,4V,20%,X6S,A E15431-004               C5D45           
CAP_A_0603V-22.0UF,4V,20%,X6S,A E15431-004               C5D46           
CAP_A_0603V-22.0UF,4V,20%,X6S,A E15431-004               C5D47           
CAP_A_0603V-22.0UF,4V,20%,X6S,A E15431-004               C5D48           
CAP_A_0603V-22.0UF,4V,20%,X6S,A E15431-004               C5D49           
CAP_A_0603V-22.0UF,4V,20%,X6S,A E15431-004               C5D50           
CAP_A_0603V-22.0UF,4V,20%,X6S,A E15431-004               C5D51           
CAP_A_0603V-22.0UF,4V,20%,X6S,A E15431-004               C5D52           
CAP_A_0603V-22.0UF,4V,20%,X6S,A E15431-004               C5D53           
CAP_A_0603V-22.0UF,4V,20%,X6S,A E15431-004               C5D58           
CAP_A_0603V-22.0UF,4V,20%,X6S,A E15431-004               C5D59           
CAP_A_0603V-22.0UF,4V,20%,X6S,A E15431-004               C5D60           
CAP_A_0603V-22.0UF,4V,20%,X6S,A E15431-004               C5D61           
CAP_A_0603V-22.0UF,4V,20%,X6S,A E15431-004               C5G1            
CAP_A_0603V-22.0UF,4V,20%,X6S,A E15431-004               C5G2            
CAP_A_0603V-22.0UF,4V,20%,X6S,A E15431-004               C5G3            
CAP_A_0603V-22.0UF,4V,20%,X6S,A E15431-004               C5G4            
CAP_A_0603V-22.0UF,4V,20%,X6S,A E15431-004               C5G5            
CAP_A_0603V-22.0UF,4V,20%,X6S,A E15431-004               C5G6            
CAP_A_0603V-22.0UF,4V,20%,X6S,A E15431-004               C5G7            
CAP_A_0603V-22.0UF,4V,20%,X6S,A E15431-004               C5G8            
CAP_A_0603V-22.0UF,4V,20%,X6S,A E15431-004               C5G11           
CAP_A_0603V-22.0UF,4V,20%,X6S,A E15431-004               C5G12           
CAP_A_0603V-22.0UF,4V,20%,X6S,A E15431-004               C5G13           
CAP_A_0603V-22.0UF,4V,20%,X6S,A E15431-004               C5G14           
CAP_A_0603V-22.0UF,4V,20%,X6S,A E15431-004               C5G15           
CAP_A_0603V-22.0UF,4V,20%,X6S,A E15431-004               C5G16           
CAP_A_0603V-22.0UF,4V,20%,X6S,A E15431-004               C5G17           
CAP_A_0603V-22.0UF,4V,20%,X6S,A E15431-004               C5G18           
CAP_A_0603V-22.0UF,4V,20%,X6S,A E15431-004               C5G41           
CAP_A_0603V-22.0UF,4V,20%,X6S,A E15431-004               C5G42           
CAP_A_0603V-22.0UF,4V,20%,X6S,A E15431-004               C5G43           
CAP_A_0603V-22.0UF,4V,20%,X6S,A E15431-004               C5G44           
CAP_A_0603V-22.0UF,4V,20%,X6S,A E15431-004               C5G45           
CAP_A_0603V-22.0UF,4V,20%,X6S,A E15431-004               C5G46           
CAP_A_0603V-22.0UF,4V,20%,X6S,A E15431-004               C5G47           
CAP_A_0603V-22.0UF,4V,20%,X6S,A E15431-004               C5G48           
CAP_A_0603V-22.0UF,4V,20%,X6S,A E15431-004               C5G49           
CAP_A_0603V-22.0UF,4V,20%,X6S,A E15431-004               C5G50           
CAP_A_0603V-22.0UF,4V,20%,X6S,A E15431-004               C5G51           
CAP_A_0603V-22.0UF,4V,20%,X6S,A E15431-004               C5G52           
CAP_A_0603V-22.0UF,4V,20%,X6S,A E15431-004               C5G53           
CAP_A_0603V-22.0UF,4V,20%,X6S,A E15431-004               C5G54           
CAP_A_0603V-22.0UF,4V,20%,X6S,A E15431-004               C5G55           
CAP_A_0603V-22.0UF,4V,20%,X6S,A E15431-004               C5G56           
CAP_A_0603V-22.0UF,4V,20%,X6S,A E15431-004               C5G57           
CAP_A_0603V-22.0UF,4V,20%,X6S,A E15431-004               C5G58           
CAP_A_0603V-22.0UF,4V,20%,X6S,A E15431-004               C5G59           
CAP_A_0603V-22.0UF,4V,20%,X6S,A E15431-004               C5G60           
CAP_A_0603V-22.0UF,4V,20%,X6S,A E15431-004               C5G61           
CAP_A_0603V-22.0UF,4V,20%,X6S,A E15431-004               C5G62           
CAP_A_0603V-22.0UF,4V,20%,X6S,A E15431-004               C5G63           
CAP_A_0603V-22.0UF,4V,20%,X6S,A E15431-004               C5G64           
CAP_A_0603V-22.0UF,4V,20%,X6S,A E15431-004               C5G65           
CAP_A_0603V-22.0UF,4V,20%,X6S,A E15431-004               C5G66           
CAP_A_0603V-22.0UF,4V,20%,X6S,A E15431-004               C5G67           
CAP_A_0603V-22.0UF,4V,20%,X6S,A E15431-004               C5G68           
CAP_A_0603V-22.0UF,4V,20%,X6S,A E15431-004               C5G69           
CAP_A_0603V-22.0UF,4V,20%,X6S,A E15431-004               C5G70           
CAP_A_0603V-22.0UF,4V,20%,X6S,A E15431-004               C5G71           
CAP_A_0603V-22.0UF,4V,20%,X6S,A E15431-004               C5G72           
CAP_A_0603V-22.0UF,4V,20%,X6S,A E15431-004               C5G73           
CAP_A_0603V-22.0UF,4V,20%,X6S,A E15431-004               C5G74           
CAP_A_0603V-22.0UF,4V,20%,X6S,A E15431-004               C5G75           
CAP_A_0603V-22.0UF,4V,20%,X6S,A E15431-004               C5G76           
CAP_A_0603V-22.0UF,4V,20%,X6S,A E15431-004               C5G79           
CAP_A_0603V-22.0UF,4V,20%,X6S,A E15431-004               C5G80           
CAP_A_0603V-22.0UF,4V,20%,X6S,A E15431-004               C5G81           
CAP_A_0603V-22.0UF,4V,20%,X6S,A E15431-004               C5G82           
CAP_A_0603V-22.0UF,4V,20%,X6S,A E15431-004               C5G83           
CAP_A_0603V-22.0UF,4V,20%,X6S,A E15431-004               C5G84           
CAP_A_0603V-22.0UF,4V,20%,X6S,A E15431-004               C5G85           
CAP_A_0603V-22.0UF,4V,20%,X6S,A E15431-004               C5G86           
CAP_A_0603V-22.0UF,4V,20%,X6S,A E15431-004               C5G87           
CAP_A_0603V-22.0UF,4V,20%,X6S,A E15431-004               C5G88           
CAP_A_0603V-22.0UF,4V,20%,X6S,A E15431-004               C5G89           
CAP_A_0603V-22.0UF,4V,20%,X6S,A E15431-004               C5G90           
CAP_A_0603V-22.0UF,4V,20%,X6S,A E15431-004               C5G91           
CAP_A_0603V-22.0UF,4V,20%,X6S,A E15431-004               C5G92           
CAP_A_0603V-22.0UF,4V,20%,X6S,A E15431-004               C5G93           
CAP_A_0603V-22.0UF,4V,20%,X6S,A E15431-004               C5G94           
CAP_A_0603V-22.0UF,4V,20%,X6S,A E15431-004               C5G95           
CAP_A_0603V-22.0UF,4V,20%,X6S,A E15431-004               C5G96           
CAP_A_0603V-22.0UF,4V,20%,X6S,A E15431-004               C5G97           
CAP_A_0603V-22.0UF,4V,20%,X6S,A E15431-004               C5G98           
CAP_A_0603V-22.0UF,4V,20%,X6S,A E15431-004               C5G99           
CAP_A_0603V-22.0UF,4V,20%,X6S,A E15431-004               C5G100          
CAP_A_0603V-22.0UF,4V,20%,X6S,A E15431-004               C5G101          
CAP_A_0603V-22.0UF,4V,20%,X6S,A E15431-004               C5G102          
CAP_A_0603V-22.0UF,4V,20%,X6S,A E15431-004               C5G103          
CAP_A_0603V-22.0UF,4V,20%,X6S,A E15431-004               C5G104          
CAP_A_0603V-22.0UF,4V,20%,X6S,A E15431-004               C5G105          
CAP_A_0603V-22.0UF,4V,20%,X6S,A E15431-004               C5G106          
CAP_A_0603V-22.0UF,4V,20%,X6S,A E15431-004               C5G107          
CAP_A_0603V-22.0UF,4V,20%,X6S,A E15431-004               C5G108          
CAP_A_0603V-22.0UF,4V,20%,X6S,A E15431-004               C5G109          
CAP_A_0603V-22.0UF,4V,20%,X6S,A E15431-004               C5G110          
CAP_A_0603V-22.0UF,4V,20%,X6S,A E15431-004               C5G111          
CAP_A_0603V-22.0UF,4V,20%,X6S,A E15431-004               C5G112          
CAP_A_0603V-22.0UF,4V,20%,X6S,A E15431-004               C5G113          
CAP_A_0603V-22.0UF,4V,20%,X6S,A E15431-004               C5G114          
CAP_A_0603V-22.0UF,4V,20%,X6S,A E15431-004               C5L6            
CAP_A_0603V-22.0UF,4V,20%,X6S,A E15431-004               C5L7            
CAP_A_0603V-22.0UF,4V,20%,X6S,A E15431-004               C5L8            
CAP_A_0603V-22.0UF,4V,20%,X6S,A E15431-004               C5L9            
CAP_A_0603V-22.0UF,4V,20%,X6S,A E15431-004               C5L10           
CAP_A_0603V-22.0UF,4V,20%,X6S,A E15431-004               C5L11           
CAP_A_0603V-22.0UF,4V,20%,X6S,A E15431-004               C5L12           
CAP_A_0603V-22.0UF,4V,20%,X6S,A E15431-004               C5L13           
CAP_A_0603V-22.0UF,4V,20%,X6S,A E15431-004               C5M1            
CAP_A_0603V-22.0UF,4V,20%,X6S,A E15431-004               C5M2            
CAP_A_0603V-22.0UF,4V,20%,X6S,A E15431-004               C5M4            
CAP_A_0603V-22.0UF,4V,20%,X6S,A E15431-004               C5M5            
CAP_A_0603V-22.0UF,4V,20%,X6S,A E15431-004               C5M6            
CAP_A_0603V-22.0UF,4V,20%,X6S,A E15431-004               C5M7            
CAP_A_0603V-22.0UF,4V,20%,X6S,A E15431-004               C5T5            
CAP_A_0603V-22.0UF,4V,20%,X6S,A E15431-004               C5T6            
CAP_A_0603V-22.0UF,4V,20%,X6S,A E15431-004               C5T7            
CAP_A_0603V-22.0UF,4V,20%,X6S,A E15431-004               C5T8            
CAP_A_0603V-22.0UF,4V,20%,X6S,A E15431-004               C5T9            
CAP_A_0603V-22.0UF,4V,20%,X6S,A E15431-004               C5T10           
CAP_A_0603V-22.0UF,4V,20%,X6S,A E15431-004               C5T11           
CAP_A_0603V-22.0UF,4V,20%,X6S,A E15431-004               C5T12           
CAP_A_0603V-22.0UF,4V,20%,X6S,A E15431-004               C5U2            
CAP_A_0603V-22.0UF,4V,20%,X6S,A E15431-004               C5U3            
CAP_A_0603V-22.0UF,4V,20%,X6S,A E15431-004               C5U4            
CAP_A_0603V-22.0UF,4V,20%,X6S,A E15431-004               C5U5            
CAP_A_0603V-22.0UF,4V,20%,X6S,A E15431-004               C5U6            
CAP_A_0603V-22.0UF,4V,20%,X6S,A E15431-004               C5U7            
CAP_A_0603V-22.0UF,4V,20%,X6S,A E15431-004               C5U8            
CAP_A_0603V-22.0UF,4V,20%,X6S,A E15431-004               C5U9            
CAP_A_0603V-22.0UF,4V,20%,X6S,A E15431-004               C6D2            
CAP_A_0603V-22.0UF,4V,20%,X6S,A E15431-004               C6D3            
CAP_A_0603V-22.0UF,4V,20%,X6S,A E15431-004               C6D4            
CAP_A_0603V-22.0UF,4V,20%,X6S,A E15431-004               C6D5            
CAP_A_0603V-22.0UF,4V,20%,X6S,A E15431-004               C6D6            
CAP_A_0603V-22.0UF,4V,20%,X6S,A E15431-004               C6D7            
CAP_A_0603V-22.0UF,4V,20%,X6S,A E15431-004               C6D8            
CAP_A_0603V-22.0UF,4V,20%,X6S,A E15431-004               C6D9            
CAP_A_0603V-22.0UF,4V,20%,X6S,A E15431-004               C6D10           
CAP_A_0603V-22.0UF,4V,20%,X6S,A E15431-004               C6N7            
CAP_A_0603V-22.0UF,4V,20%,X6S,A E15431-004               C6P3            
CAP_A_0603V-22.0UF,4V,20%,X6S,A E15431-004               C6P16           
CAP_A_0603V-22.0UF,4V,20%,X6S,A E15431-004               C6P21           
CAP_A_0603V-22.0UF,4V,20%,X6S,A E15431-004               C6R2            
CAP_A_0603V-22.0UF,4V,20%,X6S,A E15431-004               C6R7            
CAP_A_0603V-22.0UF,4V,20%,X6S,A E15431-004               C7A36           
CAP_A_0603V-22.0UF,4V,20%,X6S,A E15431-004               C7B15           
CAP_A_0603V-22.0UF,4V,20%,X6S,A E15431-004               C7B16           
CAP_A_0603V-22.0UF,4V,20%,X6S,A E15431-004               C7B17           
CAP_A_0603V-22.0UF,4V,20%,X6S,A E15431-004               C7B18           
CAP_A_0603V-22.0UF,4V,20%,X6S,A E15431-004               C7B19           
CAP_A_0603V-22.0UF,4V,20%,X6S,A E15431-004               C7B20           
CAP_A_0603V-22.0UF,4V,20%,X6S,A E15431-004               C7B21           
CAP_A_0603V-22.0UF,4V,20%,X6S,A E15431-004               C7B22           
CAP_A_0603V-22.0UF,4V,20%,X6S,A E15431-004               C7B23           
CAP_A_0603V-22.0UF,4V,20%,X6S,A E15431-004               C7B24           
CAP_A_0603V-22.0UF,4V,20%,X6S,A E15431-004               C7C6            
CAP_A_0603V-22.0UF,4V,20%,X6S,A E15431-004               C7C9            
CAP_A_0603V-22.0UF,4V,20%,X6S,A E15431-004               C7C10           
CAP_A_0603V-22.0UF,4V,20%,X6S,A E15431-004               C7D3            
CAP_A_0603V-22.0UF,4V,20%,X6S,A E15431-004               C7L4            
CAP_A_0603V-22.0UF,4V,20%,X6S,A E15431-004               C7L5            
CAP_A_0603V-22.0UF,4V,20%,X6S,A E15431-004               C7M1            
CAP_A_0603V-22.0UF,4V,20%,X6S,A E15431-004               C7M2            
CAP_A_0603V-22.0UF,4V,20%,X6S,A E15431-004               C7P12           
CAP_A_0603V-22.0UF,4V,20%,X6S,A E15431-004               C7P16           
CAP_A_0603V-22.0UF,4V,20%,X6S,A E15431-004               C7R1            
CAP_A_0603V-22.0UF,4V,20%,X6S,A E15431-004               C7T4            
CAP_A_0603V-22.0UF,4V,20%,X6S,A E15431-004               C7T5            
CAP_A_0603V-22.0UF,4V,20%,X6S,A E15431-004               C7U1            
CAP_A_0603V-22.0UF,4V,20%,X6S,A E15431-004               C7U2            
CAP_A_0603V-22.0UF,4V,20%,X6S,A E15431-004               C8B1            
CAP_A_0603V-22.0UF,4V,20%,X6S,A E15431-004               C8B2            
CAP_A_0603V-22.0UF,4V,20%,X6S,A E15431-004               C8B3            
CAP_A_0603V-22.0UF,4V,20%,X6S,A E15431-004               C8B4            
CAP_A_0603V-22.0UF,4V,20%,X6S,A E15431-004               C8B9            
CAP_A_0603V-22.0UF,4V,20%,X6S,A E15431-004               C8B10           
CAP_A_0603V-22.0UF,4V,20%,X6S,A E15431-004               C8B11           
CAP_A_0603V-22.0UF,4V,20%,X6S,A E15431-004               C8B13           
CAP_A_0603V-22.0UF,4V,20%,X6S,A E15431-004               C8B14           
CAP_A_0603V-22.0UF,4V,20%,X6S,A E15431-004               C8L5            
CAP_A_0603V-22.0UF,4V,20%,X6S,A E15431-004               C8L6            
CAP_A_0603V-22.0UF,4V,20%,X6S,A E15431-004               C8L7            
CAP_A_0603V-22.0UF,4V,20%,X6S,A E15431-004               C8L8            
CAP_A_0603V-22.0UF,4V,20%,X6S,A E15431-004               C8L9            
CAP_A_0603V-22.0UF,4V,20%,X6S,A E15431-004               C8L10           
CAP_A_0603V-22.0UF,4V,20%,X6S,A E15431-004               C8M1            
CAP_A_0603V-22.0UF,4V,20%,X6S,A E15431-004               C8M3            
CAP_A_0603V-22.0UF,4V,20%,X6S,A E15431-004               C8M4            
CAP_A_0603V-22.0UF,4V,20%,X6S,A E15431-004               C8M5            
CAP_A_0603V-22.0UF,4V,20%,X6S,A E15431-004               C8M6            
CAP_A_0603V-22.0UF,4V,20%,X6S,A E15431-004               C8T5            
CAP_A_0603V-22.0UF,4V,20%,X6S,A E15431-004               C8T6            
CAP_A_0603V-22.0UF,4V,20%,X6S,A E15431-004               C8T7            
CAP_A_0603V-22.0UF,4V,20%,X6S,A E15431-004               C8T8            
CAP_A_0603V-22.0UF,4V,20%,X6S,A E15431-004               C8T9            
CAP_A_0603V-22.0UF,4V,20%,X6S,A E15431-004               C8T10           
CAP_A_0603V-22.0UF,4V,20%,X6S,A E15431-004               C8U2            
CAP_A_0603V-22.0UF,4V,20%,X6S,A E15431-004               C8U3            
CAP_A_0603V-22.0UF,4V,20%,X6S,A E15431-004               C8U4            
CAP_A_0603V-22.0UF,4V,20%,X6S,A E15431-004               C8U5            
CAP_A_0603V-22.0UF,4V,20%,X6S,A E15431-004               C8U6            
CAP_A_0603V-22.0UF,4V,20%,X6S,A E15431-004               C8U7            
CAP_A_0603V-22.0UF,4V,20%,X6S,A E15431-004               C9N22           
CAP_A_0603V-22.0UF,4V,20%,X6S,A E15431-004               C9P3            
CAP_A_0603V-22.0UF,4V,20%,X6S,A E15431-004               C9P10           
CAP_A_0603V-22.0UF,4V,20%,X6S,A E15431-004               C9P20           
CAP_A_0603V-22.0UF,4V,20%,X6S,A E15431-004               C9R2            
CAP_A_0603V-22.0UF,4V,20%,X6S,A E15431-004               C9R8            

----------------

CAP_A_0603V-47UF,4V,20%,X5R,60A 602433-106               C2A5            
CAP_A_0603V-47UF,4V,20%,X5R,60A 602433-106               C2B1            
CAP_A_0603V-47UF,4V,20%,X5R,60A 602433-106               C2B2            
CAP_A_0603V-47UF,4V,20%,X5R,60A 602433-106               C2F1            
CAP_A_0603V-47UF,4V,20%,X5R,60A 602433-106               C2F2            
CAP_A_0603V-47UF,4V,20%,X5R,60A 602433-106               C2G8            
CAP_A_0603V-47UF,4V,20%,X5R,60A 602433-106               C2G15           
CAP_A_0603V-47UF,4V,20%,X5R,60A 602433-106               C3F1            
CAP_A_0603V-47UF,4V,20%,X5R,60A 602433-106               C3T1            
CAP_A_0603V-47UF,4V,20%,X5R,60A 602433-106               C3T2            
CAP_A_0603V-47UF,4V,20%,X5R,60A 602433-106               C4F2            
CAP_A_0603V-47UF,4V,20%,X5R,60A 602433-106               C4M5            
CAP_A_0603V-47UF,4V,20%,X5R,60A 602433-106               C5A5            
CAP_A_0603V-47UF,4V,20%,X5R,60A 602433-106               C5B1            
CAP_A_0603V-47UF,4V,20%,X5R,60A 602433-106               C5B2            
CAP_A_0603V-47UF,4V,20%,X5R,60A 602433-106               C5F1            
CAP_A_0603V-47UF,4V,20%,X5R,60A 602433-106               C5F2            
CAP_A_0603V-47UF,4V,20%,X5R,60A 602433-106               C5G10           
CAP_A_0603V-47UF,4V,20%,X5R,60A 602433-106               C5G19           
CAP_A_0603V-47UF,4V,20%,X5R,60A 602433-106               C5L4            
CAP_A_0603V-47UF,4V,20%,X5R,60A 602433-106               C5L5            
CAP_A_0603V-47UF,4V,20%,X5R,60A 602433-106               C5L15           
CAP_A_0603V-47UF,4V,20%,X5R,60A 602433-106               C5M3            
CAP_A_0603V-47UF,4V,20%,X5R,60A 602433-106               C5M9            
CAP_A_0603V-47UF,4V,20%,X5R,60A 602433-106               C5M10           
CAP_A_0603V-47UF,4V,20%,X5R,60A 602433-106               C5M11           
CAP_A_0603V-47UF,4V,20%,X5R,60A 602433-106               C5M13           
CAP_A_0603V-47UF,4V,20%,X5R,60A 602433-106               C5T1            
CAP_A_0603V-47UF,4V,20%,X5R,60A 602433-106               C5T2            
CAP_A_0603V-47UF,4V,20%,X5R,60A 602433-106               C5T3            
CAP_A_0603V-47UF,4V,20%,X5R,60A 602433-106               C5T4            
CAP_A_0603V-47UF,4V,20%,X5R,60A 602433-106               C5T13           
CAP_A_0603V-47UF,4V,20%,X5R,60A 602433-106               C5U11           
CAP_A_0603V-47UF,4V,20%,X5R,60A 602433-106               C5U12           
CAP_A_0603V-47UF,4V,20%,X5R,60A 602433-106               C5U16           
CAP_A_0603V-47UF,4V,20%,X5R,60A 602433-106               C7M5            
CAP_A_0603V-47UF,4V,20%,X5R,60A 602433-106               C8L3            
CAP_A_0603V-47UF,4V,20%,X5R,60A 602433-106               C8L4            
CAP_A_0603V-47UF,4V,20%,X5R,60A 602433-106               C8L12           
CAP_A_0603V-47UF,4V,20%,X5R,60A 602433-106               C8M2            
CAP_A_0603V-47UF,4V,20%,X5R,60A 602433-106               C8M8            
CAP_A_0603V-47UF,4V,20%,X5R,60A 602433-106               C8M9            
CAP_A_0603V-47UF,4V,20%,X5R,60A 602433-106               C8M10           
CAP_A_0603V-47UF,4V,20%,X5R,60A 602433-106               C8M12           
CAP_A_0603V-47UF,4V,20%,X5R,60A 602433-106               C8T1            
CAP_A_0603V-47UF,4V,20%,X5R,60A 602433-106               C8T2            
CAP_A_0603V-47UF,4V,20%,X5R,60A 602433-106               C8T3            
CAP_A_0603V-47UF,4V,20%,X5R,60A 602433-106               C8T4            
CAP_A_0603V-47UF,4V,20%,X5R,60A 602433-106               C8T11           
CAP_A_0603V-47UF,4V,20%,X5R,60A 602433-106               C8U9            
CAP_A_0603V-47UF,4V,20%,X5R,60A 602433-106               C8U10           
CAP_A_0603V-47UF,4V,20%,X5R,60A 602433-106               C8U13           

----------------

CHOKE_4PIN_SMLF-90 OHM,EMPTY,7A 752402-015               L1M2            

----------------

CHOKE_4PIN_SM_B-67 OHM,EMPTY,7A 752402-028               L1L1            
CHOKE_4PIN_SM_B-67 OHM,EMPTY,7A 752402-028               L1M1            

----------------

CONN12_C73564003_PIP-CONN,C735A C73564-003               J7G3            
CONN12_C73564003_PIP-CONN,C735A C73564-003               J8G2            
CONN12_C73564003_PIP-CONN,C735A C73564-003               J9G1            

----------------

CONN12_G98257001_THMT-CONN,G98A G98257-001               J1D1            
CONN12_G98257001_THMT-CONN,G98A G98257-001               J1E1            

----------------

CONN14_H54902001_PIP-CONN,H549A H54902-001               J9A2            

----------------

CONN17_H71061002_PIP1-CONN,H71A H71061-002               JA9G1           

----------------

CONN36_G97614001_CP-CONN,G9761A G97614-001               J8A2            

----------------

CONN3_C95678002_PIP-CONN,C9567A C95678-002               J1B3            
CONN3_C95678002_PIP-CONN,C9567A C95678-002               J8C1            
CONN3_C95678002_PIP-CONN,C9567A C95678-002               J8D4            
CONN3_C95678002_PIP-CONN,C9567A C95678-002               J9B2            

----------------

CONN3_G98259001_PIP-CONN,G9825A G98259-001               RM1E1           

----------------

CONN4_D42317002_PIP-CONN,D4231A D42317-002               J9A1            

----------------

CONN4_H73295001_PIP-CONN,H7329A H73295-001               J2L1            

----------------

CONN4_H73295001_PIP-EMPTY,H732A H73295-001               J8A4            

----------------

CONN6_C74770005_PIP-HDR,C74770A C74770-005               J1B2            
CONN6_C74770005_PIP-HDR,C74770A C74770-005               J1F2            

----------------

CONN72_G97614002_A_CP-CONN,G97A G97614-002               J8A1            

----------------

CONN76_H22707001_THMT1-CONN,H2A H22707-001               J1C1            
CONN76_H22707001_THMT1-CONN,H2A H22707-001               J1F1            

----------------

CONN7_E82125014_PIP_TH-CONN,E8A E82125-014               J2M1            

----------------

CONN7_E82125014_PIP_TH-EMPTY,EA E82125-014               J8A3            

----------------

CONN8_C77962004_PIP-CONN,C7796A C77962-004               J7G2            

----------------

CONN8_H62179001_PIP-CONN,H6217A H62179-001               J1F3            

----------------

CONN9_H51826001_PIP2-CONN,H518A H51826-001               J9B1            

----------------

CRYSTAL_2013-25.000MHZ,IC,D717A D71700-057               Y9E1            

----------------

CRYSTAL_2013-25.000MHZ,IC,H196A H19611-001               Y8C1            

----------------

CRYSTAL_2013-48.000MHZ,IC,D717A D71700-058               Y7C1            

----------------

CRYSTAL_2013LF-25.000MHZ,IC,D7B D71700-033               Y8F1            

----------------

CRYSTAL_SM-24.000MHZ,IC,D95126A D95126-001               Y9F1            

----------------

CRYSTAL_SM-32.768KHZ,IC,C13544A C13544-023               Y7C2            

----------------

CSD87384M_SM-IC,H66258-001 H66258-001               EU8E1           

----------------

DIODE2A_DUAL_SMLF-BAS70-05,DIOA C90169-001               CR2U1           

----------------

DIODEAC_DUAL_ARRAY_SM9-ESD3V3UA G18435-001               CR1M1           
DIODEAC_DUAL_ARRAY_SM9-ESD3V3UA G18435-001               CR1M2           

----------------

DIODE_SM-1N4148W,IC,D89194-001 D89194-001               CR1L1           
DIODE_SM-1N4148W,IC,D89194-001 D89194-001               CR1L2           
DIODE_SM-1N4148W,IC,D89194-001 D89194-001               CR1L3           
DIODE_SM-1N4148W,IC,D89194-001 D89194-001               CR1L4           

----------------

DIODE_SM-MBRS340T3G,EMPTY,C819A C81983-002               CR1F5           

----------------

DIODE_SM-SDMK0340L,EMPTY,H7179A H71799-001               CR1B1           
DIODE_SM-SDMK0340L,EMPTY,H7179A H71799-001               CR1E1           

----------------

DIODE_SM-SDMK0340L,IC,H71799-0A H71799-001               CR1B2           
DIODE_SM-SDMK0340L,IC,H71799-0A H71799-001               CR1B3           
DIODE_SM-SDMK0340L,IC,H71799-0A H71799-001               CR1F1           
DIODE_SM-SDMK0340L,IC,H71799-0A H71799-001               CR1F2           
DIODE_SM-SDMK0340L,IC,H71799-0A H71799-001               CR1F3           
DIODE_SM-SDMK0340L,IC,H71799-0A H71799-001               CR1F4           

----------------

DIODE_SMLF-1N5819HW,IC,D55839-A D55839-001               CR3U1           

----------------

DIODE_SMLF-BAT54WS,IC,C73510-0A C73510-001               CR7E1           
DIODE_SMLF-BAT54WS,IC,C73510-0A C73510-001               CR8E1           
DIODE_SMLF-BAT54WS,IC,C73510-0A C73510-001               CR9P1           
DIODE_SMLF-BAT54WS,IC,C73510-0A C73510-001               CR9P2           

----------------

FERRITE_SM-120,FB,693286-027 693286-027               FB2M1           
FERRITE_SM-120,FB,693286-027 693286-027               FB2M2           
FERRITE_SM-120,FB,693286-027 693286-027               FB3M1           
FERRITE_SM-120,FB,693286-027 693286-027               FB3M2           
FERRITE_SM-120,FB,693286-027 693286-027               FB3M3           
FERRITE_SM-120,FB,693286-027 693286-027               FB3M4           

----------------

FERRITE_SM-22,FB,656554-051 656554-051               FB4A1           
FERRITE_SM-22,FB,656554-051 656554-051               FB4G1           
FERRITE_SM-22,FB,656554-051 656554-051               FB7B1           
FERRITE_SM-22,FB,656554-051 656554-051               FB7E1           
FERRITE_SM-22,FB,656554-051 656554-051               FB7F1           
FERRITE_SM-22,FB,656554-051 656554-051               FB9E1           

----------------

FERRITE_SMLF-30,FB,693286-021 693286-021               FB1U3           
FERRITE_SMLF-30,FB,693286-021 693286-021               FB1U4           

----------------

FERRITE_SMLF-300,EMPTY,693286-A 693286-046               FB1T1           
FERRITE_SMLF-300,EMPTY,693286-A 693286-046               FB2T1           

----------------

FERRITE_SMLF-300,FB,693286-046 693286-046               FB1T2           
FERRITE_SMLF-300,FB,693286-046 693286-046               FB1U1           
FERRITE_SMLF-300,FB,693286-046 693286-046               FB9F1           

----------------

FERRITE_SMLF-60,FB,693286-001 693286-001               FB1U2           

----------------

FERRITE_SMLF-600,FB,656554-043 656554-043               FB2T2           
FERRITE_SMLF-600,FB,656554-043 656554-043               FB6P1           

----------------

FET_N_DUAL_SMLF-2N7002DW,FET,DA D24280-001               Q1D1            
FET_N_DUAL_SMLF-2N7002DW,FET,DA D24280-001               Q1L4            
FET_N_DUAL_SMLF-2N7002DW,FET,DA D24280-001               Q9P1            

----------------

FET_N_DUAL_SMLF-NTJD4001N,FET,A E40049-001               Q1L2            
FET_N_DUAL_SMLF-NTJD4001N,FET,A E40049-001               Q2U1            
FET_N_DUAL_SMLF-NTJD4001N,FET,A E40049-001               Q3U1            
FET_N_DUAL_SMLF-NTJD4001N,FET,A E40049-001               Q4B1            
FET_N_DUAL_SMLF-NTJD4001N,FET,A E40049-001               Q4B2            
FET_N_DUAL_SMLF-NTJD4001N,FET,A E40049-001               Q4U1            
FET_N_DUAL_SMLF-NTJD4001N,FET,A E40049-001               Q7E1            
FET_N_DUAL_SMLF-NTJD4001N,FET,A E40049-001               Q7E2            
FET_N_DUAL_SMLF-NTJD4001N,FET,A E40049-001               Q7E3            
FET_N_DUAL_SMLF-NTJD4001N,FET,A E40049-001               Q7E5            
FET_N_DUAL_SMLF-NTJD4001N,FET,A E40049-001               Q7E6            
FET_N_DUAL_SMLF-NTJD4001N,FET,A E40049-001               Q9A2            
FET_N_DUAL_SMLF-NTJD4001N,FET,A E40049-001               Q9E1            
FET_N_DUAL_SMLF-NTJD4001N,FET,A E40049-001               Q9F1            
FET_N_DUAL_SMLF-NTJD4001N,FET,A E40049-001               Q9G1            

----------------

FET_N_SOT23-2N7002,FET,C79254-A C79254-001               Q2P2            
FET_N_SOT23-2N7002,FET,C79254-A C79254-001               Q6F1            
FET_N_SOT23-2N7002,FET,C79254-A C79254-001               Q7D1            
FET_N_SOT23-2N7002,FET,C79254-A C79254-001               Q7E4            
FET_N_SOT23-2N7002,FET,C79254-A C79254-001               Q7E8            
FET_N_SOT23-2N7002,FET,C79254-A C79254-001               Q8D2            

----------------

FET_N_SOT23LF-2N7002,FET,C7925A C79254-001               Q1D2            
FET_N_SOT23LF-2N7002,FET,C7925A C79254-001               Q2P1            
FET_N_SOT23LF-2N7002,FET,C7925A C79254-001               Q2T2            
FET_N_SOT23LF-2N7002,FET,C7925A C79254-001               Q8E1            
FET_N_SOT23LF-2N7002,FET,C7925A C79254-001               Q8E2            
FET_N_SOT23LF-2N7002,FET,C7925A C79254-001               Q8F1            
FET_N_SOT23LF-2N7002,FET,C7925A C79254-001               Q8F2            
FET_N_SOT23LF-2N7002,FET,C7925A C79254-001               Q9A3            

----------------

FSA3357_SM-IC,C63273-001 C63273-001               U9F1            
FSA3357_SM-IC,C63273-001 C63273-001               U9F2            

----------------

FUSE_SM-IC,C94311-016 C94311-016               F9B1            

----------------

FUSE_SMLF-IC,C94311-006 C94311-006               F8B1            

----------------

FUSE_SMT-IC,H45581-001 H45581-001               F1L1            

----------------

GTL2014_SM-IC,D66151-001 D66151-001               U2T4            
GTL2014_SM-IC,D66151-001 D66151-001               U3P1            
GTL2014_SM-IC,D66151-001 D66151-001               U3P2            
GTL2014_SM-IC,D66151-001 D66151-001               U4C2            
GTL2014_SM-IC,D66151-001 D66151-001               U7D2            
GTL2014_SM-IC,D66151-001 D66151-001               U9G1            

----------------

ICS9FGP204_MLFP-IC,E95226-001 E95226-001               EU8F2           

----------------

INDUCTOR_SM-0.12UH,IND,D92183-A D92183-034               L1A1            
INDUCTOR_SM-0.12UH,IND,D92183-A D92183-034               L1A2            
INDUCTOR_SM-0.12UH,IND,D92183-A D92183-034               L1C2            
INDUCTOR_SM-0.12UH,IND,D92183-A D92183-034               L1D1            
INDUCTOR_SM-0.12UH,IND,D92183-A D92183-034               L1D2            
INDUCTOR_SM-0.12UH,IND,D92183-A D92183-034               L1D3            
INDUCTOR_SM-0.12UH,IND,D92183-A D92183-034               L1E1            
INDUCTOR_SM-0.12UH,IND,D92183-A D92183-034               L1F2            
INDUCTOR_SM-0.12UH,IND,D92183-A D92183-034               L1G1            
INDUCTOR_SM-0.12UH,IND,D92183-A D92183-034               L4C3            
INDUCTOR_SM-0.12UH,IND,D92183-A D92183-034               L4D1            
INDUCTOR_SM-0.12UH,IND,D92183-A D92183-034               L4D2            
INDUCTOR_SM-0.12UH,IND,D92183-A D92183-034               L4D3            
INDUCTOR_SM-0.12UH,IND,D92183-A D92183-034               L4E1            
INDUCTOR_SM-0.12UH,IND,D92183-A D92183-034               L7A1            
INDUCTOR_SM-0.12UH,IND,D92183-A D92183-034               L7A3            
INDUCTOR_SM-0.12UH,IND,D92183-A D92183-034               L7G1            
INDUCTOR_SM-0.12UH,IND,D92183-A D92183-034               L7G2            

----------------

INDUCTOR_SM-0.3UH,IND,D92183-0A D92183-036               L1C1            
INDUCTOR_SM-0.3UH,IND,D92183-0A D92183-036               L4C2            
INDUCTOR_SM-0.3UH,IND,D92183-0A D92183-036               L7A2            
INDUCTOR_SM-0.3UH,IND,D92183-0A D92183-036               L7A4            

----------------

INDUCTOR_SM-0.47UH,IND,E13358-A E13358-018               L4A1            
INDUCTOR_SM-0.47UH,IND,E13358-A E13358-018               L4G1            
INDUCTOR_SM-0.47UH,IND,E13358-A E13358-018               L7B1            
INDUCTOR_SM-0.47UH,IND,E13358-A E13358-018               L7F1            

----------------

INDUCTOR_SM-1.00UH,IND,E98679-A E98679-006               L8F1            

----------------

INDUCTOR_SM-100NH,IND,D92183-0A D92183-019               L1B2            
INDUCTOR_SM-100NH,IND,D92183-0A D92183-019               L4C1            

----------------

INDUCTOR_SM-100NH,IND,D92183-0B D92183-020               L1B1            
INDUCTOR_SM-100NH,IND,D92183-0B D92183-020               L1F1            
INDUCTOR_SM-100NH,IND,D92183-0B D92183-020               L7A5            
INDUCTOR_SM-100NH,IND,D92183-0B D92183-020               L7C1            
INDUCTOR_SM-100NH,IND,D92183-0B D92183-020               L7F2            

----------------

INDUCTOR_SM-150NH,IND,D92183-0A D92183-021               L4E2            
INDUCTOR_SM-150NH,IND,D92183-0A D92183-021               L7C2            

----------------

INDUCTOR_SM-2.2UH,IND,E98761-0A E98761-003               L8E1            

----------------

INDUCTOR_SMT-0.022UH,IND,72189A 721891-082               L2M1            

----------------

IR354XX_SM-IR35411,IC,H73688-0A H73688-001               EU1A1           
IR354XX_SM-IR35411,IC,H73688-0A H73688-001               EU1A2           
IR354XX_SM-IR35411,IC,H73688-0A H73688-001               EU1C3           
IR354XX_SM-IR35411,IC,H73688-0A H73688-001               EU1D1           
IR354XX_SM-IR35411,IC,H73688-0A H73688-001               EU1D3           
IR354XX_SM-IR35411,IC,H73688-0A H73688-001               EU1D4           
IR354XX_SM-IR35411,IC,H73688-0A H73688-001               EU1E2           
IR354XX_SM-IR35411,IC,H73688-0A H73688-001               EU1F1           
IR354XX_SM-IR35411,IC,H73688-0A H73688-001               EU1G1           
IR354XX_SM-IR35411,IC,H73688-0A H73688-001               EU4C2           
IR354XX_SM-IR35411,IC,H73688-0A H73688-001               EU4D1           
IR354XX_SM-IR35411,IC,H73688-0A H73688-001               EU4D3           
IR354XX_SM-IR35411,IC,H73688-0A H73688-001               EU4D6           
IR354XX_SM-IR35411,IC,H73688-0A H73688-001               EU4E1           
IR354XX_SM-IR35411,IC,H73688-0A H73688-001               EU7A1           
IR354XX_SM-IR35411,IC,H73688-0A H73688-001               EU7A4           
IR354XX_SM-IR35411,IC,H73688-0A H73688-001               EU7G2           
IR354XX_SM-IR35411,IC,H73688-0A H73688-001               EU7G3           

----------------

IR354XX_SM-IR35412,IC,H73684-0A H73684-001               EU1C1           
IR354XX_SM-IR35412,IC,H73684-0A H73684-001               EU4C1           
IR354XX_SM-IR35412,IC,H73684-0A H73684-001               EU4E2           
IR354XX_SM-IR35412,IC,H73684-0A H73684-001               EU7A2           
IR354XX_SM-IR35412,IC,H73684-0A H73684-001               EU7A3           
IR354XX_SM-IR35412,IC,H73684-0A H73684-001               EU7C1           

----------------

K4B1G16_BGA1-IC,G38649-001 G38649-001               U9F5            

----------------

LBG_CORE_QAT_EXT_D_BGA1-IC,H91A H91415-002               U7C1            

----------------

LCMXO2_A_256BGA-IC,H63395-001 H63395-001               U8D7            

----------------

LED_1NC-BLUE,IC,C96565-012 C96565-012               DS9A1           

----------------

LED_1NCLF-GREEN,IC,C96565-011 C96565-011               DS9A2           

----------------

LED_1NCLF-YELLOW,IC,C96565-003 C96565-003               DS9A3           

----------------

LED_A1-RED,IC,D14725-005 D14725-005               DS9F1           

----------------

LED_A1LF-GREEN,IC,C97278-010 C97278-010               DS9A5           
LED_A1LF-GREEN,IC,C97278-010 C97278-010               DS9A6           
LED_A1LF-GREEN,IC,C97278-010 C97278-010               DS9E1           

----------------

LED_A1LF-GREEN,IC,D14725-022 D14725-022               DS9A4           
LED_A1LF-GREEN,IC,D14725-022 D14725-022               DS9A7           

----------------

M25PE16_SM-IC,H77797-001 H77797-001               U9E1            

----------------

MAX9634_SOT-IC,H35789-001 H35789-001               U1B1            
MAX9634_SOT-IC,H35789-001 H35789-001               U1F1            
MAX9634_SOT-IC,H35789-001 H35789-001               U4B1            
MAX9634_SOT-IC,H35789-001 H35789-001               U4F1            

----------------

MIC5166_DFN-IC,H55101-001 H55101-001               EU4A1           
MIC5166_DFN-IC,H55101-001 H55101-001               EU4A2           
MIC5166_DFN-IC,H55101-001 H55101-001               EU4G2           
MIC5166_DFN-IC,H55101-001 H55101-001               EU4G3           

----------------

MOSFETN_1D3S_SOT5-IC,G68777-001 G68777-001               EU1E1           
MOSFETN_1D3S_SOT5-IC,G68777-001 G68777-001               EU1E3           
MOSFETN_1D3S_SOT5-IC,G68777-001 G68777-001               EU9R1           

----------------

MOSFET_N_LCC3-BSZ019N03LS,NFETA G26762-001               Q1B1            
MOSFET_N_LCC3-BSZ019N03LS,NFETA G26762-001               Q7E7            
MOSFET_N_LCC3-BSZ019N03LS,NFETA G26762-001               Q8B1            
MOSFET_N_LCC3-BSZ019N03LS,NFETA G26762-001               Q8G1            

----------------

MTG_KEYHOLE_TH-EMPTY,NA NA                       TH1A1           
MTG_KEYHOLE_TH-EMPTY,NA NA                       TH4A1           
MTG_KEYHOLE_TH-EMPTY,NA NA                       TH4G1           
MTG_KEYHOLE_TH-EMPTY,NA NA                       TH7A1           
MTG_KEYHOLE_TH-EMPTY,NA NA                       TH7G1           
MTG_KEYHOLE_TH-EMPTY,NA NA                       TH9A1           
MTG_KEYHOLE_TH-EMPTY,NA NA                       TH9G1           

----------------

NB3W1200L_LCC-IC,H13585-001 H13585-001               EU4D2           

----------------

NC7SB3157_SMLF-IC,C99406-001 C99406-001               U1M2            
NC7SB3157_SMLF-IC,C99406-001 C99406-001               U1M7            
NC7SB3157_SMLF-IC,C99406-001 C99406-001               U2M1            

----------------

NCP3232L_SM-IC,H86355-001 H86355-001               EU4A3           
NCP3232L_SM-IC,H86355-001 H86355-001               EU4G1           
NCP3232L_SM-IC,H86355-001 H86355-001               EU7B1           
NCP3232L_SM-IC,H86355-001 H86355-001               EU7F1           

----------------

NPN_DUAL_SSOPLF-MBT3904,EMPTY,A C52264-001               Q9A1            

----------------

NPN_DUAL_SSOPLF-MBT3904,XSTR,CA C52264-001               Q8D1            

----------------

NPN_SM-MMBT3904,IC,C52245-001 C52245-001               Q1D3            
NPN_SM-MMBT3904,IC,C52245-001 C52245-001               Q1L1            
NPN_SM-MMBT3904,IC,C52245-001 C52245-001               Q1L3            
NPN_SM-MMBT3904,IC,C52245-001 C52245-001               Q2T1            
NPN_SM-MMBT3904,IC,C52245-001 C52245-001               Q9T1            

----------------

OSC_C_6P10-156.25MHZ,OSC,G6383A G63831-004               Y3F1            
OSC_C_6P10-156.25MHZ,OSC,G6383A G63831-004               Y6F1            

----------------

OSC_C_SM4-24MHZ,OSC,D34520-021 D34520-021               Y9F2            

----------------

PCA9517_SM-IC,G77073-001-GND=GA G77073-001               U1B2            

----------------

PCA9617_SSOP-IC,G81764-001-GNDA G81764-001               U3B1            
PCA9617_SSOP-IC,G81764-001-GNDA G81764-001               U4G1            
PCA9617_SSOP-IC,G81764-001-GNDA G81764-001               U6F1            
PCA9617_SSOP-IC,G81764-001-GNDA G81764-001               U7E1            

----------------

PI3B3257A_TSSOPLF-IC,E16801-001 E16801-001               U2T1            
PI3B3257A_TSSOPLF-IC,E16801-001 E16801-001               U8F1            

----------------

PI7C9X1172_QFN-IC,H66899-001 H66899-001               EU9F3           

----------------

PNP_TO92-MPS2907,IC,G73554-001 G73554-001               Q1E1            
PNP_TO92-MPS2907,IC,G73554-001 G73554-001               Q9B1            

----------------

PXE1110B_QFN-IC,H89187-001 H89187-001               EU3P1           
PXE1110B_QFN-IC,H89187-001 H89187-001               EU4D5           
PXE1110B_QFN-IC,H89187-001 H89187-001               EU8A1           

----------------

PXE1610B_QFN-IC,H79206-001 H79206-001               EU1C2           
PXE1610B_QFN-IC,H79206-001 H79206-001               EU4D4           

----------------

PXM1310B_QFN-IC,H89186-001 H89186-001               EU1B1           
PXM1310B_QFN-IC,H89186-001 H89186-001               EU1G2           
PXM1310B_QFN-IC,H89186-001 H89186-001               EU7A5           
PXM1310B_QFN-IC,H89186-001 H89186-001               EU7G1           

----------------

RCC_DFX1940_ID4-EMPTY,N_A N_A                      TC1A1           
RCC_DFX1940_ID4-EMPTY,N_A N_A                      TC1G1           
RCC_DFX1940_ID4-EMPTY,N_A N_A                      TC9A1           
RCC_DFX1940_ID4-EMPTY,N_A N_A                      TC9F1           

----------------

RES_0402-0.0,5%,1/16W,CHIP,G21A G21497-005               R1B10           
RES_0402-0.0,5%,1/16W,CHIP,G21A G21497-005               R1B11           
RES_0402-0.0,5%,1/16W,CHIP,G21A G21497-005               R1B14           
RES_0402-0.0,5%,1/16W,CHIP,G21A G21497-005               R1C2            
RES_0402-0.0,5%,1/16W,CHIP,G21A G21497-005               R1C3            
RES_0402-0.0,5%,1/16W,CHIP,G21A G21497-005               R1C5            
RES_0402-0.0,5%,1/16W,CHIP,G21A G21497-005               R1C7            
RES_0402-0.0,5%,1/16W,CHIP,G21A G21497-005               R1C14           
RES_0402-0.0,5%,1/16W,CHIP,G21A G21497-005               R1C23           
RES_0402-0.0,5%,1/16W,CHIP,G21A G21497-005               R1C25           
RES_0402-0.0,5%,1/16W,CHIP,G21A G21497-005               R1D2            
RES_0402-0.0,5%,1/16W,CHIP,G21A G21497-005               R1D3            
RES_0402-0.0,5%,1/16W,CHIP,G21A G21497-005               R1D24           
RES_0402-0.0,5%,1/16W,CHIP,G21A G21497-005               R1D25           
RES_0402-0.0,5%,1/16W,CHIP,G21A G21497-005               R1D44           
RES_0402-0.0,5%,1/16W,CHIP,G21A G21497-005               R1D45           
RES_0402-0.0,5%,1/16W,CHIP,G21A G21497-005               R1E6            
RES_0402-0.0,5%,1/16W,CHIP,G21A G21497-005               R1E7            
RES_0402-0.0,5%,1/16W,CHIP,G21A G21497-005               R1F8            
RES_0402-0.0,5%,1/16W,CHIP,G21A G21497-005               R1G9            
RES_0402-0.0,5%,1/16W,CHIP,G21A G21497-005               R1G10           
RES_0402-0.0,5%,1/16W,CHIP,G21A G21497-005               R1G19           
RES_0402-0.0,5%,1/16W,CHIP,G21A G21497-005               R1G21           
RES_0402-0.0,5%,1/16W,CHIP,G21A G21497-005               R1G27           
RES_0402-0.0,5%,1/16W,CHIP,G21A G21497-005               R1G28           
RES_0402-0.0,5%,1/16W,CHIP,G21A G21497-005               R1L6            
RES_0402-0.0,5%,1/16W,CHIP,G21A G21497-005               R1L12           
RES_0402-0.0,5%,1/16W,CHIP,G21A G21497-005               R1L40           
RES_0402-0.0,5%,1/16W,CHIP,G21A G21497-005               R1L42           
RES_0402-0.0,5%,1/16W,CHIP,G21A G21497-005               R1M1            
RES_0402-0.0,5%,1/16W,CHIP,G21A G21497-005               R1M2            
RES_0402-0.0,5%,1/16W,CHIP,G21A G21497-005               R1M5            
RES_0402-0.0,5%,1/16W,CHIP,G21A G21497-005               R1M6            
RES_0402-0.0,5%,1/16W,CHIP,G21A G21497-005               R1M10           
RES_0402-0.0,5%,1/16W,CHIP,G21A G21497-005               R1M13           
RES_0402-0.0,5%,1/16W,CHIP,G21A G21497-005               R1M15           
RES_0402-0.0,5%,1/16W,CHIP,G21A G21497-005               R1M16           
RES_0402-0.0,5%,1/16W,CHIP,G21A G21497-005               R1M17           
RES_0402-0.0,5%,1/16W,CHIP,G21A G21497-005               R1M18           
RES_0402-0.0,5%,1/16W,CHIP,G21A G21497-005               R1R1            
RES_0402-0.0,5%,1/16W,CHIP,G21A G21497-005               R1R8            
RES_0402-0.0,5%,1/16W,CHIP,G21A G21497-005               R1T36           
RES_0402-0.0,5%,1/16W,CHIP,G21A G21497-005               R1T37           
RES_0402-0.0,5%,1/16W,CHIP,G21A G21497-005               R1U3            
RES_0402-0.0,5%,1/16W,CHIP,G21A G21497-005               R1U8            
RES_0402-0.0,5%,1/16W,CHIP,G21A G21497-005               R1U11           
RES_0402-0.0,5%,1/16W,CHIP,G21A G21497-005               R1U51           
RES_0402-0.0,5%,1/16W,CHIP,G21A G21497-005               R1U53           
RES_0402-0.0,5%,1/16W,CHIP,G21A G21497-005               R1U54           
RES_0402-0.0,5%,1/16W,CHIP,G21A G21497-005               R1U58           
RES_0402-0.0,5%,1/16W,CHIP,G21A G21497-005               R1U59           
RES_0402-0.0,5%,1/16W,CHIP,G21A G21497-005               R1U60           
RES_0402-0.0,5%,1/16W,CHIP,G21A G21497-005               R2L1            
RES_0402-0.0,5%,1/16W,CHIP,G21A G21497-005               R2L7            
RES_0402-0.0,5%,1/16W,CHIP,G21A G21497-005               R2L14           
RES_0402-0.0,5%,1/16W,CHIP,G21A G21497-005               R2L17           
RES_0402-0.0,5%,1/16W,CHIP,G21A G21497-005               R2N20           
RES_0402-0.0,5%,1/16W,CHIP,G21A G21497-005               R2N21           
RES_0402-0.0,5%,1/16W,CHIP,G21A G21497-005               R2P1            
RES_0402-0.0,5%,1/16W,CHIP,G21A G21497-005               R2P14           
RES_0402-0.0,5%,1/16W,CHIP,G21A G21497-005               R2R4            
RES_0402-0.0,5%,1/16W,CHIP,G21A G21497-005               R2R12           
RES_0402-0.0,5%,1/16W,CHIP,G21A G21497-005               R2T2            
RES_0402-0.0,5%,1/16W,CHIP,G21A G21497-005               R2T17           
RES_0402-0.0,5%,1/16W,CHIP,G21A G21497-005               R2T20           
RES_0402-0.0,5%,1/16W,CHIP,G21A G21497-005               R2T27           
RES_0402-0.0,5%,1/16W,CHIP,G21A G21497-005               R2T32           
RES_0402-0.0,5%,1/16W,CHIP,G21A G21497-005               R2T40           
RES_0402-0.0,5%,1/16W,CHIP,G21A G21497-005               R2T44           
RES_0402-0.0,5%,1/16W,CHIP,G21A G21497-005               R2T60           
RES_0402-0.0,5%,1/16W,CHIP,G21A G21497-005               R2T64           
RES_0402-0.0,5%,1/16W,CHIP,G21A G21497-005               R2T65           
RES_0402-0.0,5%,1/16W,CHIP,G21A G21497-005               R2T66           
RES_0402-0.0,5%,1/16W,CHIP,G21A G21497-005               R2T67           
RES_0402-0.0,5%,1/16W,CHIP,G21A G21497-005               R2T68           
RES_0402-0.0,5%,1/16W,CHIP,G21A G21497-005               R2U37           
RES_0402-0.0,5%,1/16W,CHIP,G21A G21497-005               R2U46           
RES_0402-0.0,5%,1/16W,CHIP,G21A G21497-005               R2U47           
RES_0402-0.0,5%,1/16W,CHIP,G21A G21497-005               R3B3            
RES_0402-0.0,5%,1/16W,CHIP,G21A G21497-005               R3B5            
RES_0402-0.0,5%,1/16W,CHIP,G21A G21497-005               R3D18           
RES_0402-0.0,5%,1/16W,CHIP,G21A G21497-005               R3F2            
RES_0402-0.0,5%,1/16W,CHIP,G21A G21497-005               R3F4            
RES_0402-0.0,5%,1/16W,CHIP,G21A G21497-005               R3L9            
RES_0402-0.0,5%,1/16W,CHIP,G21A G21497-005               R3L10           
RES_0402-0.0,5%,1/16W,CHIP,G21A G21497-005               R3M1            
RES_0402-0.0,5%,1/16W,CHIP,G21A G21497-005               R3M6            
RES_0402-0.0,5%,1/16W,CHIP,G21A G21497-005               R3P1            
RES_0402-0.0,5%,1/16W,CHIP,G21A G21497-005               R3P2            
RES_0402-0.0,5%,1/16W,CHIP,G21A G21497-005               R3P3            
RES_0402-0.0,5%,1/16W,CHIP,G21A G21497-005               R3P11           
RES_0402-0.0,5%,1/16W,CHIP,G21A G21497-005               R3P22           
RES_0402-0.0,5%,1/16W,CHIP,G21A G21497-005               R3P26           
RES_0402-0.0,5%,1/16W,CHIP,G21A G21497-005               R3P34           
RES_0402-0.0,5%,1/16W,CHIP,G21A G21497-005               R3P35           
RES_0402-0.0,5%,1/16W,CHIP,G21A G21497-005               R3P57           
RES_0402-0.0,5%,1/16W,CHIP,G21A G21497-005               R3P58           
RES_0402-0.0,5%,1/16W,CHIP,G21A G21497-005               R3P59           
RES_0402-0.0,5%,1/16W,CHIP,G21A G21497-005               R3T13           
RES_0402-0.0,5%,1/16W,CHIP,G21A G21497-005               R3U3            
RES_0402-0.0,5%,1/16W,CHIP,G21A G21497-005               R3U10           
RES_0402-0.0,5%,1/16W,CHIP,G21A G21497-005               R4A2            
RES_0402-0.0,5%,1/16W,CHIP,G21A G21497-005               R4A3            
RES_0402-0.0,5%,1/16W,CHIP,G21A G21497-005               R4A8            
RES_0402-0.0,5%,1/16W,CHIP,G21A G21497-005               R4A9            
RES_0402-0.0,5%,1/16W,CHIP,G21A G21497-005               R4B1            
RES_0402-0.0,5%,1/16W,CHIP,G21A G21497-005               R4B3            
RES_0402-0.0,5%,1/16W,CHIP,G21A G21497-005               R4B11           
RES_0402-0.0,5%,1/16W,CHIP,G21A G21497-005               R4B13           
RES_0402-0.0,5%,1/16W,CHIP,G21A G21497-005               R4B14           
RES_0402-0.0,5%,1/16W,CHIP,G21A G21497-005               R4C2            
RES_0402-0.0,5%,1/16W,CHIP,G21A G21497-005               R4C4            
RES_0402-0.0,5%,1/16W,CHIP,G21A G21497-005               R4D26           
RES_0402-0.0,5%,1/16W,CHIP,G21A G21497-005               R4D45           
RES_0402-0.0,5%,1/16W,CHIP,G21A G21497-005               R4D47           
RES_0402-0.0,5%,1/16W,CHIP,G21A G21497-005               R4D50           
RES_0402-0.0,5%,1/16W,CHIP,G21A G21497-005               R4D53           
RES_0402-0.0,5%,1/16W,CHIP,G21A G21497-005               R4D54           
RES_0402-0.0,5%,1/16W,CHIP,G21A G21497-005               R4D56           
RES_0402-0.0,5%,1/16W,CHIP,G21A G21497-005               R4D66           
RES_0402-0.0,5%,1/16W,CHIP,G21A G21497-005               R4D67           
RES_0402-0.0,5%,1/16W,CHIP,G21A G21497-005               R4E16           
RES_0402-0.0,5%,1/16W,CHIP,G21A G21497-005               R4E17           
RES_0402-0.0,5%,1/16W,CHIP,G21A G21497-005               R4F1            
RES_0402-0.0,5%,1/16W,CHIP,G21A G21497-005               R4G4            
RES_0402-0.0,5%,1/16W,CHIP,G21A G21497-005               R4G8            
RES_0402-0.0,5%,1/16W,CHIP,G21A G21497-005               R4G16           
RES_0402-0.0,5%,1/16W,CHIP,G21A G21497-005               R4G23           
RES_0402-0.0,5%,1/16W,CHIP,G21A G21497-005               R4G24           
RES_0402-0.0,5%,1/16W,CHIP,G21A G21497-005               R4G25           
RES_0402-0.0,5%,1/16W,CHIP,G21A G21497-005               R4T1            
RES_0402-0.0,5%,1/16W,CHIP,G21A G21497-005               R6B4            
RES_0402-0.0,5%,1/16W,CHIP,G21A G21497-005               R6B5            
RES_0402-0.0,5%,1/16W,CHIP,G21A G21497-005               R6F7            
RES_0402-0.0,5%,1/16W,CHIP,G21A G21497-005               R6F9            
RES_0402-0.0,5%,1/16W,CHIP,G21A G21497-005               R6L6            
RES_0402-0.0,5%,1/16W,CHIP,G21A G21497-005               R6L8            
RES_0402-0.0,5%,1/16W,CHIP,G21A G21497-005               R6L10           
RES_0402-0.0,5%,1/16W,CHIP,G21A G21497-005               R6L11           
RES_0402-0.0,5%,1/16W,CHIP,G21A G21497-005               R6N11           
RES_0402-0.0,5%,1/16W,CHIP,G21A G21497-005               R6N12           
RES_0402-0.0,5%,1/16W,CHIP,G21A G21497-005               R6P18           
RES_0402-0.0,5%,1/16W,CHIP,G21A G21497-005               R6P29           
RES_0402-0.0,5%,1/16W,CHIP,G21A G21497-005               R6P30           
RES_0402-0.0,5%,1/16W,CHIP,G21A G21497-005               R6P34           
RES_0402-0.0,5%,1/16W,CHIP,G21A G21497-005               R6P38           
RES_0402-0.0,5%,1/16W,CHIP,G21A G21497-005               R6P41           
RES_0402-0.0,5%,1/16W,CHIP,G21A G21497-005               R6P42           
RES_0402-0.0,5%,1/16W,CHIP,G21A G21497-005               R6P43           
RES_0402-0.0,5%,1/16W,CHIP,G21A G21497-005               R6U4            
RES_0402-0.0,5%,1/16W,CHIP,G21A G21497-005               R6U5            
RES_0402-0.0,5%,1/16W,CHIP,G21A G21497-005               R6U6            
RES_0402-0.0,5%,1/16W,CHIP,G21A G21497-005               R6U7            
RES_0402-0.0,5%,1/16W,CHIP,G21A G21497-005               R7A11           
RES_0402-0.0,5%,1/16W,CHIP,G21A G21497-005               R7A12           
RES_0402-0.0,5%,1/16W,CHIP,G21A G21497-005               R7A18           
RES_0402-0.0,5%,1/16W,CHIP,G21A G21497-005               R7B9            
RES_0402-0.0,5%,1/16W,CHIP,G21A G21497-005               R7B11           
RES_0402-0.0,5%,1/16W,CHIP,G21A G21497-005               R7B19           
RES_0402-0.0,5%,1/16W,CHIP,G21A G21497-005               R7B20           
RES_0402-0.0,5%,1/16W,CHIP,G21A G21497-005               R7C15           
RES_0402-0.0,5%,1/16W,CHIP,G21A G21497-005               R7C19           
RES_0402-0.0,5%,1/16W,CHIP,G21A G21497-005               R7D23           
RES_0402-0.0,5%,1/16W,CHIP,G21A G21497-005               R7D27           
RES_0402-0.0,5%,1/16W,CHIP,G21A G21497-005               R7D28           
RES_0402-0.0,5%,1/16W,CHIP,G21A G21497-005               R7D36           
RES_0402-0.0,5%,1/16W,CHIP,G21A G21497-005               R7D41           
RES_0402-0.0,5%,1/16W,CHIP,G21A G21497-005               R7E9            
RES_0402-0.0,5%,1/16W,CHIP,G21A G21497-005               R7E13           
RES_0402-0.0,5%,1/16W,CHIP,G21A G21497-005               R7E17           
RES_0402-0.0,5%,1/16W,CHIP,G21A G21497-005               R7E22           
RES_0402-0.0,5%,1/16W,CHIP,G21A G21497-005               R7F8            
RES_0402-0.0,5%,1/16W,CHIP,G21A G21497-005               R7F9            
RES_0402-0.0,5%,1/16W,CHIP,G21A G21497-005               R7F12           
RES_0402-0.0,5%,1/16W,CHIP,G21A G21497-005               R7F21           
RES_0402-0.0,5%,1/16W,CHIP,G21A G21497-005               R7F35           
RES_0402-0.0,5%,1/16W,CHIP,G21A G21497-005               R7G2            
RES_0402-0.0,5%,1/16W,CHIP,G21A G21497-005               R7G4            
RES_0402-0.0,5%,1/16W,CHIP,G21A G21497-005               R7G14           
RES_0402-0.0,5%,1/16W,CHIP,G21A G21497-005               R7G17           
RES_0402-0.0,5%,1/16W,CHIP,G21A G21497-005               R7G21           
RES_0402-0.0,5%,1/16W,CHIP,G21A G21497-005               R8B12           
RES_0402-0.0,5%,1/16W,CHIP,G21A G21497-005               R8B14           
RES_0402-0.0,5%,1/16W,CHIP,G21A G21497-005               R8C24           
RES_0402-0.0,5%,1/16W,CHIP,G21A G21497-005               R8D35           
RES_0402-0.0,5%,1/16W,CHIP,G21A G21497-005               R8D43           
RES_0402-0.0,5%,1/16W,CHIP,G21A G21497-005               R8E1            
RES_0402-0.0,5%,1/16W,CHIP,G21A G21497-005               R8E21           
RES_0402-0.0,5%,1/16W,CHIP,G21A G21497-005               R8E25           
RES_0402-0.0,5%,1/16W,CHIP,G21A G21497-005               R8E26           
RES_0402-0.0,5%,1/16W,CHIP,G21A G21497-005               R8E27           
RES_0402-0.0,5%,1/16W,CHIP,G21A G21497-005               R8E28           
RES_0402-0.0,5%,1/16W,CHIP,G21A G21497-005               R8E33           
RES_0402-0.0,5%,1/16W,CHIP,G21A G21497-005               R8E35           
RES_0402-0.0,5%,1/16W,CHIP,G21A G21497-005               R8E37           
RES_0402-0.0,5%,1/16W,CHIP,G21A G21497-005               R8E38           
RES_0402-0.0,5%,1/16W,CHIP,G21A G21497-005               R8F2            
RES_0402-0.0,5%,1/16W,CHIP,G21A G21497-005               R8F6            
RES_0402-0.0,5%,1/16W,CHIP,G21A G21497-005               R8F11           
RES_0402-0.0,5%,1/16W,CHIP,G21A G21497-005               R8F18           
RES_0402-0.0,5%,1/16W,CHIP,G21A G21497-005               R8F21           
RES_0402-0.0,5%,1/16W,CHIP,G21A G21497-005               R8F38           
RES_0402-0.0,5%,1/16W,CHIP,G21A G21497-005               R8G7            
RES_0402-0.0,5%,1/16W,CHIP,G21A G21497-005               R8G8            
RES_0402-0.0,5%,1/16W,CHIP,G21A G21497-005               R8G10           
RES_0402-0.0,5%,1/16W,CHIP,G21A G21497-005               R8G13           
RES_0402-0.0,5%,1/16W,CHIP,G21A G21497-005               R8G14           
RES_0402-0.0,5%,1/16W,CHIP,G21A G21497-005               R8G17           
RES_0402-0.0,5%,1/16W,CHIP,G21A G21497-005               R8G18           
RES_0402-0.0,5%,1/16W,CHIP,G21A G21497-005               R8G19           
RES_0402-0.0,5%,1/16W,CHIP,G21A G21497-005               R8G21           
RES_0402-0.0,5%,1/16W,CHIP,G21A G21497-005               R8G22           
RES_0402-0.0,5%,1/16W,CHIP,G21A G21497-005               R9A3            
RES_0402-0.0,5%,1/16W,CHIP,G21A G21497-005               R9A8            
RES_0402-0.0,5%,1/16W,CHIP,G21A G21497-005               R9B11           
RES_0402-0.0,5%,1/16W,CHIP,G21A G21497-005               R9B13           
RES_0402-0.0,5%,1/16W,CHIP,G21A G21497-005               R9E14           
RES_0402-0.0,5%,1/16W,CHIP,G21A G21497-005               R9E18           
RES_0402-0.0,5%,1/16W,CHIP,G21A G21497-005               R9E20           
RES_0402-0.0,5%,1/16W,CHIP,G21A G21497-005               R9F7            
RES_0402-0.0,5%,1/16W,CHIP,G21A G21497-005               R9F27           
RES_0402-0.0,5%,1/16W,CHIP,G21A G21497-005               R9F33           
RES_0402-0.0,5%,1/16W,CHIP,G21A G21497-005               R9F53           
RES_0402-0.0,5%,1/16W,CHIP,G21A G21497-005               R9F54           
RES_0402-0.0,5%,1/16W,CHIP,G21A G21497-005               R9F56           
RES_0402-0.0,5%,1/16W,CHIP,G21A G21497-005               R9F57           
RES_0402-0.0,5%,1/16W,CHIP,G21A G21497-005               R9F58           
RES_0402-0.0,5%,1/16W,CHIP,G21A G21497-005               R9F59           
RES_0402-0.0,5%,1/16W,CHIP,G21A G21497-005               R9F62           
RES_0402-0.0,5%,1/16W,CHIP,G21A G21497-005               R9F63           
RES_0402-0.0,5%,1/16W,CHIP,G21A G21497-005               R9F66           
RES_0402-0.0,5%,1/16W,CHIP,G21A G21497-005               R9F68           
RES_0402-0.0,5%,1/16W,CHIP,G21A G21497-005               R9F70           
RES_0402-0.0,5%,1/16W,CHIP,G21A G21497-005               R9G4            
RES_0402-0.0,5%,1/16W,CHIP,G21A G21497-005               R9G9            
RES_0402-0.0,5%,1/16W,CHIP,G21A G21497-005               R9G11           
RES_0402-0.0,5%,1/16W,CHIP,G21A G21497-005               R9G17           
RES_0402-0.0,5%,1/16W,CHIP,G21A G21497-005               R9G18           
RES_0402-0.0,5%,1/16W,CHIP,G21A G21497-005               R9G19           
RES_0402-0.0,5%,1/16W,CHIP,G21A G21497-005               R9G20           
RES_0402-0.0,5%,1/16W,CHIP,G21A G21497-005               R9G22           
RES_0402-0.0,5%,1/16W,CHIP,G21A G21497-005               R9G24           
RES_0402-0.0,5%,1/16W,CHIP,G21A G21497-005               R9G28           
RES_0402-0.0,5%,1/16W,CHIP,G21A G21497-005               R9G29           
RES_0402-0.0,5%,1/16W,CHIP,G21A G21497-005               R9G32           
RES_0402-0.0,5%,1/16W,CHIP,G21A G21497-005               R9G33           
RES_0402-0.0,5%,1/16W,CHIP,G21A G21497-005               R9G34           
RES_0402-0.0,5%,1/16W,CHIP,G21A G21497-005               R9M3            
RES_0402-0.0,5%,1/16W,CHIP,G21A G21497-005               R9M9            
RES_0402-0.0,5%,1/16W,CHIP,G21A G21497-005               R9M10           
RES_0402-0.0,5%,1/16W,CHIP,G21A G21497-005               R9M11           
RES_0402-0.0,5%,1/16W,CHIP,G21A G21497-005               R9M20           
RES_0402-0.0,5%,1/16W,CHIP,G21A G21497-005               R9M21           
RES_0402-0.0,5%,1/16W,CHIP,G21A G21497-005               R9N5            
RES_0402-0.0,5%,1/16W,CHIP,G21A G21497-005               R9N9            
RES_0402-0.0,5%,1/16W,CHIP,G21A G21497-005               R9N10           
RES_0402-0.0,5%,1/16W,CHIP,G21A G21497-005               R9N12           
RES_0402-0.0,5%,1/16W,CHIP,G21A G21497-005               R9N15           
RES_0402-0.0,5%,1/16W,CHIP,G21A G21497-005               R9N16           
RES_0402-0.0,5%,1/16W,CHIP,G21A G21497-005               R9N17           
RES_0402-0.0,5%,1/16W,CHIP,G21A G21497-005               R9P16           
RES_0402-0.0,5%,1/16W,CHIP,G21A G21497-005               R9P21           
RES_0402-0.0,5%,1/16W,CHIP,G21A G21497-005               R9R9            
RES_0402-0.0,5%,1/16W,CHIP,G21A G21497-005               R9R10           
RES_0402-0.0,5%,1/16W,CHIP,G21A G21497-005               R9R12           
RES_0402-0.0,5%,1/16W,CHIP,G21A G21497-005               R9T1            
RES_0402-0.0,5%,1/16W,CHIP,G21A G21497-005               R9T4            
RES_0402-0.0,5%,1/16W,CHIP,G21A G21497-005               R9U7            
RES_0402-0.0,5%,1/16W,CHIP,G21A G21497-005               R9U10           

----------------

RES_0402-0.0,5%,1/16W,EMPTY,G2A G21497-005               R1C9            
RES_0402-0.0,5%,1/16W,EMPTY,G2A G21497-005               R1C10           
RES_0402-0.0,5%,1/16W,EMPTY,G2A G21497-005               R1C11           
RES_0402-0.0,5%,1/16W,EMPTY,G2A G21497-005               R1C31           
RES_0402-0.0,5%,1/16W,EMPTY,G2A G21497-005               R1F9            
RES_0402-0.0,5%,1/16W,EMPTY,G2A G21497-005               R1T15           
RES_0402-0.0,5%,1/16W,EMPTY,G2A G21497-005               R1T23           
RES_0402-0.0,5%,1/16W,EMPTY,G2A G21497-005               R1T24           
RES_0402-0.0,5%,1/16W,EMPTY,G2A G21497-005               R1T35           
RES_0402-0.0,5%,1/16W,EMPTY,G2A G21497-005               R1T38           
RES_0402-0.0,5%,1/16W,EMPTY,G2A G21497-005               R1U55           
RES_0402-0.0,5%,1/16W,EMPTY,G2A G21497-005               R1U56           
RES_0402-0.0,5%,1/16W,EMPTY,G2A G21497-005               R1U57           
RES_0402-0.0,5%,1/16W,EMPTY,G2A G21497-005               R1U61           
RES_0402-0.0,5%,1/16W,EMPTY,G2A G21497-005               R1U62           
RES_0402-0.0,5%,1/16W,EMPTY,G2A G21497-005               R2P12           
RES_0402-0.0,5%,1/16W,EMPTY,G2A G21497-005               R2T57           
RES_0402-0.0,5%,1/16W,EMPTY,G2A G21497-005               R2T58           
RES_0402-0.0,5%,1/16W,EMPTY,G2A G21497-005               R2T59           
RES_0402-0.0,5%,1/16W,EMPTY,G2A G21497-005               R2T61           
RES_0402-0.0,5%,1/16W,EMPTY,G2A G21497-005               R2T62           
RES_0402-0.0,5%,1/16W,EMPTY,G2A G21497-005               R2T63           
RES_0402-0.0,5%,1/16W,EMPTY,G2A G21497-005               R2T69           
RES_0402-0.0,5%,1/16W,EMPTY,G2A G21497-005               R2T71           
RES_0402-0.0,5%,1/16W,EMPTY,G2A G21497-005               R2U14           
RES_0402-0.0,5%,1/16W,EMPTY,G2A G21497-005               R2U15           
RES_0402-0.0,5%,1/16W,EMPTY,G2A G21497-005               R2U16           
RES_0402-0.0,5%,1/16W,EMPTY,G2A G21497-005               R2U17           
RES_0402-0.0,5%,1/16W,EMPTY,G2A G21497-005               R2U18           
RES_0402-0.0,5%,1/16W,EMPTY,G2A G21497-005               R2U19           
RES_0402-0.0,5%,1/16W,EMPTY,G2A G21497-005               R2U20           
RES_0402-0.0,5%,1/16W,EMPTY,G2A G21497-005               R2U21           
RES_0402-0.0,5%,1/16W,EMPTY,G2A G21497-005               R2U22           
RES_0402-0.0,5%,1/16W,EMPTY,G2A G21497-005               R2U23           
RES_0402-0.0,5%,1/16W,EMPTY,G2A G21497-005               R2U24           
RES_0402-0.0,5%,1/16W,EMPTY,G2A G21497-005               R2U25           
RES_0402-0.0,5%,1/16W,EMPTY,G2A G21497-005               R2U26           
RES_0402-0.0,5%,1/16W,EMPTY,G2A G21497-005               R2U27           
RES_0402-0.0,5%,1/16W,EMPTY,G2A G21497-005               R2U28           
RES_0402-0.0,5%,1/16W,EMPTY,G2A G21497-005               R2U29           
RES_0402-0.0,5%,1/16W,EMPTY,G2A G21497-005               R2U45           
RES_0402-0.0,5%,1/16W,EMPTY,G2A G21497-005               R2U49           
RES_0402-0.0,5%,1/16W,EMPTY,G2A G21497-005               R2U50           
RES_0402-0.0,5%,1/16W,EMPTY,G2A G21497-005               R2U51           
RES_0402-0.0,5%,1/16W,EMPTY,G2A G21497-005               R3D31           
RES_0402-0.0,5%,1/16W,EMPTY,G2A G21497-005               R3F1            
RES_0402-0.0,5%,1/16W,EMPTY,G2A G21497-005               R3F3            
RES_0402-0.0,5%,1/16W,EMPTY,G2A G21497-005               R3F5            
RES_0402-0.0,5%,1/16W,EMPTY,G2A G21497-005               R3F6            
RES_0402-0.0,5%,1/16W,EMPTY,G2A G21497-005               R3N30           
RES_0402-0.0,5%,1/16W,EMPTY,G2A G21497-005               R3P63           
RES_0402-0.0,5%,1/16W,EMPTY,G2A G21497-005               R4T2            
RES_0402-0.0,5%,1/16W,EMPTY,G2A G21497-005               R6D16           
RES_0402-0.0,5%,1/16W,EMPTY,G2A G21497-005               R6F6            
RES_0402-0.0,5%,1/16W,EMPTY,G2A G21497-005               R6F8            
RES_0402-0.0,5%,1/16W,EMPTY,G2A G21497-005               R6F10           
RES_0402-0.0,5%,1/16W,EMPTY,G2A G21497-005               R6F11           
RES_0402-0.0,5%,1/16W,EMPTY,G2A G21497-005               R7C2            
RES_0402-0.0,5%,1/16W,EMPTY,G2A G21497-005               R7C4            
RES_0402-0.0,5%,1/16W,EMPTY,G2A G21497-005               R7C18           
RES_0402-0.0,5%,1/16W,EMPTY,G2A G21497-005               R7D37           
RES_0402-0.0,5%,1/16W,EMPTY,G2A G21497-005               R7D38           
RES_0402-0.0,5%,1/16W,EMPTY,G2A G21497-005               R7D39           
RES_0402-0.0,5%,1/16W,EMPTY,G2A G21497-005               R7D40           
RES_0402-0.0,5%,1/16W,EMPTY,G2A G21497-005               R7D43           
RES_0402-0.0,5%,1/16W,EMPTY,G2A G21497-005               R7G15           
RES_0402-0.0,5%,1/16W,EMPTY,G2A G21497-005               R7G16           
RES_0402-0.0,5%,1/16W,EMPTY,G2A G21497-005               R7G18           
RES_0402-0.0,5%,1/16W,EMPTY,G2A G21497-005               R7G19           
RES_0402-0.0,5%,1/16W,EMPTY,G2A G21497-005               R8C23           
RES_0402-0.0,5%,1/16W,EMPTY,G2A G21497-005               R8E11           
RES_0402-0.0,5%,1/16W,EMPTY,G2A G21497-005               R8E29           
RES_0402-0.0,5%,1/16W,EMPTY,G2A G21497-005               R8F37           
RES_0402-0.0,5%,1/16W,EMPTY,G2A G21497-005               R8G9            
RES_0402-0.0,5%,1/16W,EMPTY,G2A G21497-005               R8G11           
RES_0402-0.0,5%,1/16W,EMPTY,G2A G21497-005               R8G12           
RES_0402-0.0,5%,1/16W,EMPTY,G2A G21497-005               R8G15           
RES_0402-0.0,5%,1/16W,EMPTY,G2A G21497-005               R8G16           
RES_0402-0.0,5%,1/16W,EMPTY,G2A G21497-005               R9E15           
RES_0402-0.0,5%,1/16W,EMPTY,G2A G21497-005               R9F24           
RES_0402-0.0,5%,1/16W,EMPTY,G2A G21497-005               R9F26           
RES_0402-0.0,5%,1/16W,EMPTY,G2A G21497-005               R9F60           
RES_0402-0.0,5%,1/16W,EMPTY,G2A G21497-005               R9F64           
RES_0402-0.0,5%,1/16W,EMPTY,G2A G21497-005               R9F65           
RES_0402-0.0,5%,1/16W,EMPTY,G2A G21497-005               R9F67           
RES_0402-0.0,5%,1/16W,EMPTY,G2A G21497-005               R9F69           
RES_0402-0.0,5%,1/16W,EMPTY,G2A G21497-005               R9G5            
RES_0402-0.0,5%,1/16W,EMPTY,G2A G21497-005               R9G6            
RES_0402-0.0,5%,1/16W,EMPTY,G2A G21497-005               R9G27           
RES_0402-0.0,5%,1/16W,EMPTY,G2A G21497-005               R9G30           
RES_0402-0.0,5%,1/16W,EMPTY,G2A G21497-005               R9P15           
RES_0402-0.0,5%,1/16W,EMPTY,G2A G21497-005               R9T8            

----------------

RES_0402-1.0,1%,1/16W,CHIP,G21A G21796-090               R3L1            
RES_0402-1.0,1%,1/16W,CHIP,G21A G21796-090               R3L4            
RES_0402-1.0,1%,1/16W,CHIP,G21A G21796-090               R3L6            
RES_0402-1.0,1%,1/16W,CHIP,G21A G21796-090               R3L8            
RES_0402-1.0,1%,1/16W,CHIP,G21A G21796-090               R3N7            
RES_0402-1.0,1%,1/16W,CHIP,G21A G21796-090               R3U6            
RES_0402-1.0,1%,1/16W,CHIP,G21A G21796-090               R3U9            
RES_0402-1.0,1%,1/16W,CHIP,G21A G21796-090               R6N3            
RES_0402-1.0,1%,1/16W,CHIP,G21A G21796-090               R6P10           
RES_0402-1.0,1%,1/16W,CHIP,G21A G21796-090               R6P19           
RES_0402-1.0,1%,1/16W,CHIP,G21A G21796-090               R6P47           
RES_0402-1.0,1%,1/16W,CHIP,G21A G21796-090               R6R2            
RES_0402-1.0,1%,1/16W,CHIP,G21A G21796-090               R6R5            
RES_0402-1.0,1%,1/16W,CHIP,G21A G21796-090               R6R6            
RES_0402-1.0,1%,1/16W,CHIP,G21A G21796-090               R9L4            
RES_0402-1.0,1%,1/16W,CHIP,G21A G21796-090               R9L9            
RES_0402-1.0,1%,1/16W,CHIP,G21A G21796-090               R9N3            
RES_0402-1.0,1%,1/16W,CHIP,G21A G21796-090               R9P8            
RES_0402-1.0,1%,1/16W,CHIP,G21A G21796-090               R9P22           
RES_0402-1.0,1%,1/16W,CHIP,G21A G21796-090               R9P32           
RES_0402-1.0,1%,1/16W,CHIP,G21A G21796-090               R9R2            
RES_0402-1.0,1%,1/16W,CHIP,G21A G21796-090               R9R11           
RES_0402-1.0,1%,1/16W,CHIP,G21A G21796-090               R9U1            
RES_0402-1.0,1%,1/16W,CHIP,G21A G21796-090               R9U12           

----------------

RES_0402-1.00K,1%,1/16W,CHIP,GA G21796-026               R1B1            
RES_0402-1.00K,1%,1/16W,CHIP,GA G21796-026               R1B2            
RES_0402-1.00K,1%,1/16W,CHIP,GA G21796-026               R1C28           
RES_0402-1.00K,1%,1/16W,CHIP,GA G21796-026               R1C32           
RES_0402-1.00K,1%,1/16W,CHIP,GA G21796-026               R1C33           
RES_0402-1.00K,1%,1/16W,CHIP,GA G21796-026               R1C36           
RES_0402-1.00K,1%,1/16W,CHIP,GA G21796-026               R1D6            
RES_0402-1.00K,1%,1/16W,CHIP,GA G21796-026               R1D8            
RES_0402-1.00K,1%,1/16W,CHIP,GA G21796-026               R1D36           
RES_0402-1.00K,1%,1/16W,CHIP,GA G21796-026               R1E9            
RES_0402-1.00K,1%,1/16W,CHIP,GA G21796-026               R1E10           
RES_0402-1.00K,1%,1/16W,CHIP,GA G21796-026               R1F5            
RES_0402-1.00K,1%,1/16W,CHIP,GA G21796-026               R1F6            
RES_0402-1.00K,1%,1/16W,CHIP,GA G21796-026               R1G2            
RES_0402-1.00K,1%,1/16W,CHIP,GA G21796-026               R1G3            
RES_0402-1.00K,1%,1/16W,CHIP,GA G21796-026               R1G11           
RES_0402-1.00K,1%,1/16W,CHIP,GA G21796-026               R1G15           
RES_0402-1.00K,1%,1/16W,CHIP,GA G21796-026               R1G16           
RES_0402-1.00K,1%,1/16W,CHIP,GA G21796-026               R1G17           
RES_0402-1.00K,1%,1/16W,CHIP,GA G21796-026               R1L3            
RES_0402-1.00K,1%,1/16W,CHIP,GA G21796-026               R1L5            
RES_0402-1.00K,1%,1/16W,CHIP,GA G21796-026               R1L13           
RES_0402-1.00K,1%,1/16W,CHIP,GA G21796-026               R1L23           
RES_0402-1.00K,1%,1/16W,CHIP,GA G21796-026               R1L36           
RES_0402-1.00K,1%,1/16W,CHIP,GA G21796-026               R1L38           
RES_0402-1.00K,1%,1/16W,CHIP,GA G21796-026               R1M19           
RES_0402-1.00K,1%,1/16W,CHIP,GA G21796-026               R1M20           
RES_0402-1.00K,1%,1/16W,CHIP,GA G21796-026               R1M21           
RES_0402-1.00K,1%,1/16W,CHIP,GA G21796-026               R1T11           
RES_0402-1.00K,1%,1/16W,CHIP,GA G21796-026               R1T12           
RES_0402-1.00K,1%,1/16W,CHIP,GA G21796-026               R1T29           
RES_0402-1.00K,1%,1/16W,CHIP,GA G21796-026               R1T30           
RES_0402-1.00K,1%,1/16W,CHIP,GA G21796-026               R1U17           
RES_0402-1.00K,1%,1/16W,CHIP,GA G21796-026               R1U18           
RES_0402-1.00K,1%,1/16W,CHIP,GA G21796-026               R1U30           
RES_0402-1.00K,1%,1/16W,CHIP,GA G21796-026               R1U33           
RES_0402-1.00K,1%,1/16W,CHIP,GA G21796-026               R1U63           
RES_0402-1.00K,1%,1/16W,CHIP,GA G21796-026               R1U64           
RES_0402-1.00K,1%,1/16W,CHIP,GA G21796-026               R2L18           
RES_0402-1.00K,1%,1/16W,CHIP,GA G21796-026               R2L22           
RES_0402-1.00K,1%,1/16W,CHIP,GA G21796-026               R2M4            
RES_0402-1.00K,1%,1/16W,CHIP,GA G21796-026               R2N18           
RES_0402-1.00K,1%,1/16W,CHIP,GA G21796-026               R2P2            
RES_0402-1.00K,1%,1/16W,CHIP,GA G21796-026               R2R5            
RES_0402-1.00K,1%,1/16W,CHIP,GA G21796-026               R2T1            
RES_0402-1.00K,1%,1/16W,CHIP,GA G21796-026               R2T5            
RES_0402-1.00K,1%,1/16W,CHIP,GA G21796-026               R2T7            
RES_0402-1.00K,1%,1/16W,CHIP,GA G21796-026               R2T25           
RES_0402-1.00K,1%,1/16W,CHIP,GA G21796-026               R2T50           
RES_0402-1.00K,1%,1/16W,CHIP,GA G21796-026               R2U43           
RES_0402-1.00K,1%,1/16W,CHIP,GA G21796-026               R3M10           
RES_0402-1.00K,1%,1/16W,CHIP,GA G21796-026               R3N15           
RES_0402-1.00K,1%,1/16W,CHIP,GA G21796-026               R3N16           
RES_0402-1.00K,1%,1/16W,CHIP,GA G21796-026               R3P5            
RES_0402-1.00K,1%,1/16W,CHIP,GA G21796-026               R3P6            
RES_0402-1.00K,1%,1/16W,CHIP,GA G21796-026               R3P7            
RES_0402-1.00K,1%,1/16W,CHIP,GA G21796-026               R3P8            
RES_0402-1.00K,1%,1/16W,CHIP,GA G21796-026               R3P18           
RES_0402-1.00K,1%,1/16W,CHIP,GA G21796-026               R3P25           
RES_0402-1.00K,1%,1/16W,CHIP,GA G21796-026               R3P32           
RES_0402-1.00K,1%,1/16W,CHIP,GA G21796-026               R3P36           
RES_0402-1.00K,1%,1/16W,CHIP,GA G21796-026               R3P56           
RES_0402-1.00K,1%,1/16W,CHIP,GA G21796-026               R3R1            
RES_0402-1.00K,1%,1/16W,CHIP,GA G21796-026               R3R2            
RES_0402-1.00K,1%,1/16W,CHIP,GA G21796-026               R3R15           
RES_0402-1.00K,1%,1/16W,CHIP,GA G21796-026               R4B10           
RES_0402-1.00K,1%,1/16W,CHIP,GA G21796-026               R4C8            
RES_0402-1.00K,1%,1/16W,CHIP,GA G21796-026               R4C9            
RES_0402-1.00K,1%,1/16W,CHIP,GA G21796-026               R4D42           
RES_0402-1.00K,1%,1/16W,CHIP,GA G21796-026               R4D49           
RES_0402-1.00K,1%,1/16W,CHIP,GA G21796-026               R4D58           
RES_0402-1.00K,1%,1/16W,CHIP,GA G21796-026               R4E3            
RES_0402-1.00K,1%,1/16W,CHIP,GA G21796-026               R4E5            
RES_0402-1.00K,1%,1/16W,CHIP,GA G21796-026               R4F4            
RES_0402-1.00K,1%,1/16W,CHIP,GA G21796-026               R4F5            
RES_0402-1.00K,1%,1/16W,CHIP,GA G21796-026               R4G2            
RES_0402-1.00K,1%,1/16W,CHIP,GA G21796-026               R4G3            
RES_0402-1.00K,1%,1/16W,CHIP,GA G21796-026               R4G14           
RES_0402-1.00K,1%,1/16W,CHIP,GA G21796-026               R4G21           
RES_0402-1.00K,1%,1/16W,CHIP,GA G21796-026               R4G22           
RES_0402-1.00K,1%,1/16W,CHIP,GA G21796-026               R4R1            
RES_0402-1.00K,1%,1/16W,CHIP,GA G21796-026               R6L1            
RES_0402-1.00K,1%,1/16W,CHIP,GA G21796-026               R6L2            
RES_0402-1.00K,1%,1/16W,CHIP,GA G21796-026               R6L12           
RES_0402-1.00K,1%,1/16W,CHIP,GA G21796-026               R6L13           
RES_0402-1.00K,1%,1/16W,CHIP,GA G21796-026               R6L16           
RES_0402-1.00K,1%,1/16W,CHIP,GA G21796-026               R6M1            
RES_0402-1.00K,1%,1/16W,CHIP,GA G21796-026               R6N13           
RES_0402-1.00K,1%,1/16W,CHIP,GA G21796-026               R6N14           
RES_0402-1.00K,1%,1/16W,CHIP,GA G21796-026               R6N15           
RES_0402-1.00K,1%,1/16W,CHIP,GA G21796-026               R6P16           
RES_0402-1.00K,1%,1/16W,CHIP,GA G21796-026               R6P20           
RES_0402-1.00K,1%,1/16W,CHIP,GA G21796-026               R6P21           
RES_0402-1.00K,1%,1/16W,CHIP,GA G21796-026               R6T5            
RES_0402-1.00K,1%,1/16W,CHIP,GA G21796-026               R7B4            
RES_0402-1.00K,1%,1/16W,CHIP,GA G21796-026               R7B5            
RES_0402-1.00K,1%,1/16W,CHIP,GA G21796-026               R7B17           
RES_0402-1.00K,1%,1/16W,CHIP,GA G21796-026               R7D1            
RES_0402-1.00K,1%,1/16W,CHIP,GA G21796-026               R7D2            
RES_0402-1.00K,1%,1/16W,CHIP,GA G21796-026               R7D7            
RES_0402-1.00K,1%,1/16W,CHIP,GA G21796-026               R7D18           
RES_0402-1.00K,1%,1/16W,CHIP,GA G21796-026               R7D26           
RES_0402-1.00K,1%,1/16W,CHIP,GA G21796-026               R7E12           
RES_0402-1.00K,1%,1/16W,CHIP,GA G21796-026               R7E20           
RES_0402-1.00K,1%,1/16W,CHIP,GA G21796-026               R7F19           
RES_0402-1.00K,1%,1/16W,CHIP,GA G21796-026               R7F22           
RES_0402-1.00K,1%,1/16W,CHIP,GA G21796-026               R7F27           
RES_0402-1.00K,1%,1/16W,CHIP,GA G21796-026               R7G27           
RES_0402-1.00K,1%,1/16W,CHIP,GA G21796-026               R7G28           
RES_0402-1.00K,1%,1/16W,CHIP,GA G21796-026               R7G29           
RES_0402-1.00K,1%,1/16W,CHIP,GA G21796-026               R7G31           
RES_0402-1.00K,1%,1/16W,CHIP,GA G21796-026               R8A5            
RES_0402-1.00K,1%,1/16W,CHIP,GA G21796-026               R8A6            
RES_0402-1.00K,1%,1/16W,CHIP,GA G21796-026               R8B2            
RES_0402-1.00K,1%,1/16W,CHIP,GA G21796-026               R8B23           
RES_0402-1.00K,1%,1/16W,CHIP,GA G21796-026               R8B30           
RES_0402-1.00K,1%,1/16W,CHIP,GA G21796-026               R8C4            
RES_0402-1.00K,1%,1/16W,CHIP,GA G21796-026               R8C18           
RES_0402-1.00K,1%,1/16W,CHIP,GA G21796-026               R8D21           
RES_0402-1.00K,1%,1/16W,CHIP,GA G21796-026               R8D27           
RES_0402-1.00K,1%,1/16W,CHIP,GA G21796-026               R8D28           
RES_0402-1.00K,1%,1/16W,CHIP,GA G21796-026               R8E2            
RES_0402-1.00K,1%,1/16W,CHIP,GA G21796-026               R8F5            
RES_0402-1.00K,1%,1/16W,CHIP,GA G21796-026               R9A14           
RES_0402-1.00K,1%,1/16W,CHIP,GA G21796-026               R9A15           
RES_0402-1.00K,1%,1/16W,CHIP,GA G21796-026               R9A17           
RES_0402-1.00K,1%,1/16W,CHIP,GA G21796-026               R9B6            
RES_0402-1.00K,1%,1/16W,CHIP,GA G21796-026               R9B8            
RES_0402-1.00K,1%,1/16W,CHIP,GA G21796-026               R9B9            
RES_0402-1.00K,1%,1/16W,CHIP,GA G21796-026               R9B12           
RES_0402-1.00K,1%,1/16W,CHIP,GA G21796-026               R9B14           
RES_0402-1.00K,1%,1/16W,CHIP,GA G21796-026               R9F50           
RES_0402-1.00K,1%,1/16W,CHIP,GA G21796-026               R9F51           
RES_0402-1.00K,1%,1/16W,CHIP,GA G21796-026               R9L1            
RES_0402-1.00K,1%,1/16W,CHIP,GA G21796-026               R9L2            
RES_0402-1.00K,1%,1/16W,CHIP,GA G21796-026               R9L6            
RES_0402-1.00K,1%,1/16W,CHIP,GA G21796-026               R9L7            
RES_0402-1.00K,1%,1/16W,CHIP,GA G21796-026               R9L11           
RES_0402-1.00K,1%,1/16W,CHIP,GA G21796-026               R9M1            
RES_0402-1.00K,1%,1/16W,CHIP,GA G21796-026               R9N14           

----------------

RES_0402-1.00K,1%,1/16W,EMPTY,A G21796-026               R1C6            
RES_0402-1.00K,1%,1/16W,EMPTY,A G21796-026               R1E5            
RES_0402-1.00K,1%,1/16W,EMPTY,A G21796-026               R1M23           
RES_0402-1.00K,1%,1/16W,EMPTY,A G21796-026               R1T10           
RES_0402-1.00K,1%,1/16W,EMPTY,A G21796-026               R1U15           
RES_0402-1.00K,1%,1/16W,EMPTY,A G21796-026               R1U16           
RES_0402-1.00K,1%,1/16W,EMPTY,A G21796-026               R2N14           
RES_0402-1.00K,1%,1/16W,EMPTY,A G21796-026               R2N24           
RES_0402-1.00K,1%,1/16W,EMPTY,A G21796-026               R2P11           
RES_0402-1.00K,1%,1/16W,EMPTY,A G21796-026               R2R11           
RES_0402-1.00K,1%,1/16W,EMPTY,A G21796-026               R3N17           
RES_0402-1.00K,1%,1/16W,EMPTY,A G21796-026               R3P64           
RES_0402-1.00K,1%,1/16W,EMPTY,A G21796-026               R4C3            
RES_0402-1.00K,1%,1/16W,EMPTY,A G21796-026               R4E15           
RES_0402-1.00K,1%,1/16W,EMPTY,A G21796-026               R7D19           
RES_0402-1.00K,1%,1/16W,EMPTY,A G21796-026               R7E19           
RES_0402-1.00K,1%,1/16W,EMPTY,A G21796-026               R8C17           
RES_0402-1.00K,1%,1/16W,EMPTY,A G21796-026               R8D5            
RES_0402-1.00K,1%,1/16W,EMPTY,A G21796-026               R8E4            
RES_0402-1.00K,1%,1/16W,EMPTY,A G21796-026               R8E6            
RES_0402-1.00K,1%,1/16W,EMPTY,A G21796-026               R8F35           
RES_0402-1.00K,1%,1/16W,EMPTY,A G21796-026               R9A1            

----------------

RES_0402-1.0K,0.1%,1/16W,CHIP,A G85996-004               R2M6            
RES_0402-1.0K,0.1%,1/16W,CHIP,A G85996-004               R2N4            
RES_0402-1.0K,0.1%,1/16W,CHIP,A G85996-004               R2T4            
RES_0402-1.0K,0.1%,1/16W,CHIP,A G85996-004               R4B9            
RES_0402-1.0K,0.1%,1/16W,CHIP,A G85996-004               R4G10           
RES_0402-1.0K,0.1%,1/16W,CHIP,A G85996-004               R7B18           
RES_0402-1.0K,0.1%,1/16W,CHIP,A G85996-004               R7F17           
RES_0402-1.0K,0.1%,1/16W,CHIP,A G85996-004               R8E18           

----------------

RES_0402-1.0M,1%,1/16W,EMPTY,GA G21796-021               R6L4            
RES_0402-1.0M,1%,1/16W,EMPTY,GA G21796-021               R6L5            
RES_0402-1.0M,1%,1/16W,EMPTY,GA G21796-021               R6U3            
RES_0402-1.0M,1%,1/16W,EMPTY,GA G21796-021               R6U15           
RES_0402-1.0M,1%,1/16W,EMPTY,GA G21796-021               R7C11           

----------------

RES_0402-1.37K,1%,1/16W,CHIP,GA G21796-095               R7E16           
RES_0402-1.37K,1%,1/16W,CHIP,GA G21796-095               R8D15           
RES_0402-1.37K,1%,1/16W,CHIP,GA G21796-095               R8D17           

----------------

RES_0402-1.5K,1%,1/16W,CHIP,G2A G21796-003               R1B9            
RES_0402-1.5K,1%,1/16W,CHIP,G2A G21796-003               R1C16           
RES_0402-1.5K,1%,1/16W,CHIP,G2A G21796-003               R1G24           
RES_0402-1.5K,1%,1/16W,CHIP,G2A G21796-003               R1U52           
RES_0402-1.5K,1%,1/16W,CHIP,G2A G21796-003               R2L10           
RES_0402-1.5K,1%,1/16W,CHIP,G2A G21796-003               R2M8            
RES_0402-1.5K,1%,1/16W,CHIP,G2A G21796-003               R2N29           
RES_0402-1.5K,1%,1/16W,CHIP,G2A G21796-003               R3P16           
RES_0402-1.5K,1%,1/16W,CHIP,G2A G21796-003               R4D32           
RES_0402-1.5K,1%,1/16W,CHIP,G2A G21796-003               R4D57           
RES_0402-1.5K,1%,1/16W,CHIP,G2A G21796-003               R7A16           
RES_0402-1.5K,1%,1/16W,CHIP,G2A G21796-003               R7G3            

----------------

RES_0402-1.8K,1%,1/16W,CHIP,G2A G21796-336               R5N2            
RES_0402-1.8K,1%,1/16W,CHIP,G2A G21796-336               R5N4            
RES_0402-1.8K,1%,1/16W,CHIP,G2A G21796-336               R8B6            
RES_0402-1.8K,1%,1/16W,CHIP,G2A G21796-336               R8B7            
RES_0402-1.8K,1%,1/16W,CHIP,G2A G21796-336               R8B11           
RES_0402-1.8K,1%,1/16W,CHIP,G2A G21796-336               R8B13           
RES_0402-1.8K,1%,1/16W,CHIP,G2A G21796-336               R8N1            
RES_0402-1.8K,1%,1/16W,CHIP,G2A G21796-336               R8N4            

----------------

RES_0402-10.0,1%,1/16W,CHIP,G2A G21796-066               R1B16           
RES_0402-10.0,1%,1/16W,CHIP,G2A G21796-066               R1C21           
RES_0402-10.0,1%,1/16W,CHIP,G2A G21796-066               R1D4            
RES_0402-10.0,1%,1/16W,CHIP,G2A G21796-066               R1D46           
RES_0402-10.0,1%,1/16W,CHIP,G2A G21796-066               R1D47           
RES_0402-10.0,1%,1/16W,CHIP,G2A G21796-066               R1D48           
RES_0402-10.0,1%,1/16W,CHIP,G2A G21796-066               R1D51           
RES_0402-10.0,1%,1/16W,CHIP,G2A G21796-066               R1E1            
RES_0402-10.0,1%,1/16W,CHIP,G2A G21796-066               R1G5            
RES_0402-10.0,1%,1/16W,CHIP,G2A G21796-066               R1L2            
RES_0402-10.0,1%,1/16W,CHIP,G2A G21796-066               R1L11           
RES_0402-10.0,1%,1/16W,CHIP,G2A G21796-066               R1L14           
RES_0402-10.0,1%,1/16W,CHIP,G2A G21796-066               R1L18           
RES_0402-10.0,1%,1/16W,CHIP,G2A G21796-066               R1L20           
RES_0402-10.0,1%,1/16W,CHIP,G2A G21796-066               R1L24           
RES_0402-10.0,1%,1/16W,CHIP,G2A G21796-066               R1L25           
RES_0402-10.0,1%,1/16W,CHIP,G2A G21796-066               R1L30           
RES_0402-10.0,1%,1/16W,CHIP,G2A G21796-066               R1L32           
RES_0402-10.0,1%,1/16W,CHIP,G2A G21796-066               R3N9            
RES_0402-10.0,1%,1/16W,CHIP,G2A G21796-066               R3N19           
RES_0402-10.0,1%,1/16W,CHIP,G2A G21796-066               R3R7            
RES_0402-10.0,1%,1/16W,CHIP,G2A G21796-066               R3R14           
RES_0402-10.0,1%,1/16W,CHIP,G2A G21796-066               R4D39           
RES_0402-10.0,1%,1/16W,CHIP,G2A G21796-066               R4E7            
RES_0402-10.0,1%,1/16W,CHIP,G2A G21796-066               R4E8            
RES_0402-10.0,1%,1/16W,CHIP,G2A G21796-066               R4T3            
RES_0402-10.0,1%,1/16W,CHIP,G2A G21796-066               R4T4            
RES_0402-10.0,1%,1/16W,CHIP,G2A G21796-066               R6N8            
RES_0402-10.0,1%,1/16W,CHIP,G2A G21796-066               R6N9            
RES_0402-10.0,1%,1/16W,CHIP,G2A G21796-066               R6T3            
RES_0402-10.0,1%,1/16W,CHIP,G2A G21796-066               R6T4            
RES_0402-10.0,1%,1/16W,CHIP,G2A G21796-066               R7A7            
RES_0402-10.0,1%,1/16W,CHIP,G2A G21796-066               R7A14           
RES_0402-10.0,1%,1/16W,CHIP,G2A G21796-066               R7A19           
RES_0402-10.0,1%,1/16W,CHIP,G2A G21796-066               R7G9            
RES_0402-10.0,1%,1/16W,CHIP,G2A G21796-066               R7M3            
RES_0402-10.0,1%,1/16W,CHIP,G2A G21796-066               R7M8            
RES_0402-10.0,1%,1/16W,CHIP,G2A G21796-066               R8A1            
RES_0402-10.0,1%,1/16W,CHIP,G2A G21796-066               R8B20           
RES_0402-10.0,1%,1/16W,CHIP,G2A G21796-066               R9P26           
RES_0402-10.0,1%,1/16W,CHIP,G2A G21796-066               R9P27           
RES_0402-10.0,1%,1/16W,CHIP,G2A G21796-066               R9R4            

----------------

RES_0402-10.0,1%,1/16W,EMPTY,GA G21796-066               R3D32           
RES_0402-10.0,1%,1/16W,EMPTY,GA G21796-066               R5D6            

----------------

RES_0402-10.0K,1%,1/16W,CHIP,GA G21796-016               R1C34           
RES_0402-10.0K,1%,1/16W,CHIP,GA G21796-016               R1D10           
RES_0402-10.0K,1%,1/16W,CHIP,GA G21796-016               R1D12           
RES_0402-10.0K,1%,1/16W,CHIP,GA G21796-016               R1D19           
RES_0402-10.0K,1%,1/16W,CHIP,GA G21796-016               R1D22           
RES_0402-10.0K,1%,1/16W,CHIP,GA G21796-016               R1D23           
RES_0402-10.0K,1%,1/16W,CHIP,GA G21796-016               R1M11           
RES_0402-10.0K,1%,1/16W,CHIP,GA G21796-016               R1M12           
RES_0402-10.0K,1%,1/16W,CHIP,GA G21796-016               R1M24           
RES_0402-10.0K,1%,1/16W,CHIP,GA G21796-016               R1M25           
RES_0402-10.0K,1%,1/16W,CHIP,GA G21796-016               R1R4            
RES_0402-10.0K,1%,1/16W,CHIP,GA G21796-016               R1R10           
RES_0402-10.0K,1%,1/16W,CHIP,GA G21796-016               R1R12           
RES_0402-10.0K,1%,1/16W,CHIP,GA G21796-016               R1R13           
RES_0402-10.0K,1%,1/16W,CHIP,GA G21796-016               R1T1            
RES_0402-10.0K,1%,1/16W,CHIP,GA G21796-016               R1U6            
RES_0402-10.0K,1%,1/16W,CHIP,GA G21796-016               R1U7            
RES_0402-10.0K,1%,1/16W,CHIP,GA G21796-016               R2N6            
RES_0402-10.0K,1%,1/16W,CHIP,GA G21796-016               R2N9            
RES_0402-10.0K,1%,1/16W,CHIP,GA G21796-016               R2N13           
RES_0402-10.0K,1%,1/16W,CHIP,GA G21796-016               R2N16           
RES_0402-10.0K,1%,1/16W,CHIP,GA G21796-016               R2N23           
RES_0402-10.0K,1%,1/16W,CHIP,GA G21796-016               R2N28           
RES_0402-10.0K,1%,1/16W,CHIP,GA G21796-016               R2P15           
RES_0402-10.0K,1%,1/16W,CHIP,GA G21796-016               R2P16           
RES_0402-10.0K,1%,1/16W,CHIP,GA G21796-016               R2P18           
RES_0402-10.0K,1%,1/16W,CHIP,GA G21796-016               R2P19           
RES_0402-10.0K,1%,1/16W,CHIP,GA G21796-016               R2P21           
RES_0402-10.0K,1%,1/16W,CHIP,GA G21796-016               R2P22           
RES_0402-10.0K,1%,1/16W,CHIP,GA G21796-016               R2R1            
RES_0402-10.0K,1%,1/16W,CHIP,GA G21796-016               R2R3            
RES_0402-10.0K,1%,1/16W,CHIP,GA G21796-016               R2T8            
RES_0402-10.0K,1%,1/16W,CHIP,GA G21796-016               R2T22           
RES_0402-10.0K,1%,1/16W,CHIP,GA G21796-016               R3N10           
RES_0402-10.0K,1%,1/16W,CHIP,GA G21796-016               R3T4            
RES_0402-10.0K,1%,1/16W,CHIP,GA G21796-016               R3T12           
RES_0402-10.0K,1%,1/16W,CHIP,GA G21796-016               R3T14           
RES_0402-10.0K,1%,1/16W,CHIP,GA G21796-016               R4A5            
RES_0402-10.0K,1%,1/16W,CHIP,GA G21796-016               R4G5            
RES_0402-10.0K,1%,1/16W,CHIP,GA G21796-016               R4G17           
RES_0402-10.0K,1%,1/16W,CHIP,GA G21796-016               R4G18           
RES_0402-10.0K,1%,1/16W,CHIP,GA G21796-016               R4P5            
RES_0402-10.0K,1%,1/16W,CHIP,GA G21796-016               R5N1            
RES_0402-10.0K,1%,1/16W,CHIP,GA G21796-016               R5N3            
RES_0402-10.0K,1%,1/16W,CHIP,GA G21796-016               R5N5            
RES_0402-10.0K,1%,1/16W,CHIP,GA G21796-016               R6F3            
RES_0402-10.0K,1%,1/16W,CHIP,GA G21796-016               R6L9            
RES_0402-10.0K,1%,1/16W,CHIP,GA G21796-016               R7B6            
RES_0402-10.0K,1%,1/16W,CHIP,GA G21796-016               R7C5            
RES_0402-10.0K,1%,1/16W,CHIP,GA G21796-016               R7C8            
RES_0402-10.0K,1%,1/16W,CHIP,GA G21796-016               R7C13           
RES_0402-10.0K,1%,1/16W,CHIP,GA G21796-016               R7C20           
RES_0402-10.0K,1%,1/16W,CHIP,GA G21796-016               R7C21           
RES_0402-10.0K,1%,1/16W,CHIP,GA G21796-016               R7C23           
RES_0402-10.0K,1%,1/16W,CHIP,GA G21796-016               R7D4            
RES_0402-10.0K,1%,1/16W,CHIP,GA G21796-016               R7D8            
RES_0402-10.0K,1%,1/16W,CHIP,GA G21796-016               R7D10           
RES_0402-10.0K,1%,1/16W,CHIP,GA G21796-016               R7D12           
RES_0402-10.0K,1%,1/16W,CHIP,GA G21796-016               R7E5            
RES_0402-10.0K,1%,1/16W,CHIP,GA G21796-016               R7E6            
RES_0402-10.0K,1%,1/16W,CHIP,GA G21796-016               R7F1            
RES_0402-10.0K,1%,1/16W,CHIP,GA G21796-016               R7F14           
RES_0402-10.0K,1%,1/16W,CHIP,GA G21796-016               R7F28           
RES_0402-10.0K,1%,1/16W,CHIP,GA G21796-016               R7F32           
RES_0402-10.0K,1%,1/16W,CHIP,GA G21796-016               R7G22           
RES_0402-10.0K,1%,1/16W,CHIP,GA G21796-016               R7G23           
RES_0402-10.0K,1%,1/16W,CHIP,GA G21796-016               R7G26           
RES_0402-10.0K,1%,1/16W,CHIP,GA G21796-016               R7P13           
RES_0402-10.0K,1%,1/16W,CHIP,GA G21796-016               R8B32           
RES_0402-10.0K,1%,1/16W,CHIP,GA G21796-016               R8D13           
RES_0402-10.0K,1%,1/16W,CHIP,GA G21796-016               R8D30           
RES_0402-10.0K,1%,1/16W,CHIP,GA G21796-016               R8D41           
RES_0402-10.0K,1%,1/16W,CHIP,GA G21796-016               R8D44           
RES_0402-10.0K,1%,1/16W,CHIP,GA G21796-016               R8E3            
RES_0402-10.0K,1%,1/16W,CHIP,GA G21796-016               R8E30           
RES_0402-10.0K,1%,1/16W,CHIP,GA G21796-016               R8E34           
RES_0402-10.0K,1%,1/16W,CHIP,GA G21796-016               R8E36           
RES_0402-10.0K,1%,1/16W,CHIP,GA G21796-016               R8F26           
RES_0402-10.0K,1%,1/16W,CHIP,GA G21796-016               R8F32           
RES_0402-10.0K,1%,1/16W,CHIP,GA G21796-016               R8F36           
RES_0402-10.0K,1%,1/16W,CHIP,GA G21796-016               R8G20           
RES_0402-10.0K,1%,1/16W,CHIP,GA G21796-016               R8N2            
RES_0402-10.0K,1%,1/16W,CHIP,GA G21796-016               R8N3            
RES_0402-10.0K,1%,1/16W,CHIP,GA G21796-016               R8N5            
RES_0402-10.0K,1%,1/16W,CHIP,GA G21796-016               R9E1            
RES_0402-10.0K,1%,1/16W,CHIP,GA G21796-016               R9E2            
RES_0402-10.0K,1%,1/16W,CHIP,GA G21796-016               R9E3            
RES_0402-10.0K,1%,1/16W,CHIP,GA G21796-016               R9E4            
RES_0402-10.0K,1%,1/16W,CHIP,GA G21796-016               R9E13           
RES_0402-10.0K,1%,1/16W,CHIP,GA G21796-016               R9E22           
RES_0402-10.0K,1%,1/16W,CHIP,GA G21796-016               R9F8            
RES_0402-10.0K,1%,1/16W,CHIP,GA G21796-016               R9F12           
RES_0402-10.0K,1%,1/16W,CHIP,GA G21796-016               R9F13           
RES_0402-10.0K,1%,1/16W,CHIP,GA G21796-016               R9F61           
RES_0402-10.0K,1%,1/16W,CHIP,GA G21796-016               R9P5            
RES_0402-10.0K,1%,1/16W,CHIP,GA G21796-016               R9P6            
RES_0402-10.0K,1%,1/16W,CHIP,GA G21796-016               R9P9            
RES_0402-10.0K,1%,1/16W,CHIP,GA G21796-016               R9P10           
RES_0402-10.0K,1%,1/16W,CHIP,GA G21796-016               R9P11           

----------------

RES_0402-10.0K,1%,1/16W,EMPTY,A G21796-016               R1E11           
RES_0402-10.0K,1%,1/16W,EMPTY,A G21796-016               R2N12           
RES_0402-10.0K,1%,1/16W,EMPTY,A G21796-016               R2T12           
RES_0402-10.0K,1%,1/16W,EMPTY,A G21796-016               R3P50           
RES_0402-10.0K,1%,1/16W,EMPTY,A G21796-016               R3R11           
RES_0402-10.0K,1%,1/16W,EMPTY,A G21796-016               R3T9            
RES_0402-10.0K,1%,1/16W,EMPTY,A G21796-016               R4D35           
RES_0402-10.0K,1%,1/16W,EMPTY,A G21796-016               R4D38           
RES_0402-10.0K,1%,1/16W,EMPTY,A G21796-016               R7B7            
RES_0402-10.0K,1%,1/16W,EMPTY,A G21796-016               R7B8            
RES_0402-10.0K,1%,1/16W,EMPTY,A G21796-016               R7F30           
RES_0402-10.0K,1%,1/16W,EMPTY,A G21796-016               R8D16           
RES_0402-10.0K,1%,1/16W,EMPTY,A G21796-016               R8F1            
RES_0402-10.0K,1%,1/16W,EMPTY,A G21796-016               R9P19           

----------------

RES_0402-100.0,1%,1/16W,CHIP,GA G21796-017               R1B22           
RES_0402-100.0,1%,1/16W,CHIP,GA G21796-017               R1B23           
RES_0402-100.0,1%,1/16W,CHIP,GA G21796-017               R1C4            
RES_0402-100.0,1%,1/16W,CHIP,GA G21796-017               R1C12           
RES_0402-100.0,1%,1/16W,CHIP,GA G21796-017               R1E4            
RES_0402-100.0,1%,1/16W,CHIP,GA G21796-017               R1E8            
RES_0402-100.0,1%,1/16W,CHIP,GA G21796-017               R1F2            
RES_0402-100.0,1%,1/16W,CHIP,GA G21796-017               R1L39           
RES_0402-100.0,1%,1/16W,CHIP,GA G21796-017               R1L41           
RES_0402-100.0,1%,1/16W,CHIP,GA G21796-017               R1M3            
RES_0402-100.0,1%,1/16W,CHIP,GA G21796-017               R1M4            
RES_0402-100.0,1%,1/16W,CHIP,GA G21796-017               R1U37           
RES_0402-100.0,1%,1/16W,CHIP,GA G21796-017               R2P20           
RES_0402-100.0,1%,1/16W,CHIP,GA G21796-017               R2R8            
RES_0402-100.0,1%,1/16W,CHIP,GA G21796-017               R2T39           
RES_0402-100.0,1%,1/16W,CHIP,GA G21796-017               R3B4            
RES_0402-100.0,1%,1/16W,CHIP,GA G21796-017               R3D3            
RES_0402-100.0,1%,1/16W,CHIP,GA G21796-017               R3D28           
RES_0402-100.0,1%,1/16W,CHIP,GA G21796-017               R3E1            
RES_0402-100.0,1%,1/16W,CHIP,GA G21796-017               R3M11           
RES_0402-100.0,1%,1/16W,CHIP,GA G21796-017               R3M12           
RES_0402-100.0,1%,1/16W,CHIP,GA G21796-017               R3N20           
RES_0402-100.0,1%,1/16W,CHIP,GA G21796-017               R3N21           
RES_0402-100.0,1%,1/16W,CHIP,GA G21796-017               R3P49           
RES_0402-100.0,1%,1/16W,CHIP,GA G21796-017               R3U2            
RES_0402-100.0,1%,1/16W,CHIP,GA G21796-017               R4C1            
RES_0402-100.0,1%,1/16W,CHIP,GA G21796-017               R4C5            
RES_0402-100.0,1%,1/16W,CHIP,GA G21796-017               R4E10           
RES_0402-100.0,1%,1/16W,CHIP,GA G21796-017               R4E14           
RES_0402-100.0,1%,1/16W,CHIP,GA G21796-017               R4E18           
RES_0402-100.0,1%,1/16W,CHIP,GA G21796-017               R4P11           
RES_0402-100.0,1%,1/16W,CHIP,GA G21796-017               R4P12           
RES_0402-100.0,1%,1/16W,CHIP,GA G21796-017               R4P15           
RES_0402-100.0,1%,1/16W,CHIP,GA G21796-017               R6B2            
RES_0402-100.0,1%,1/16W,CHIP,GA G21796-017               R6D1            
RES_0402-100.0,1%,1/16W,CHIP,GA G21796-017               R6N2            
RES_0402-100.0,1%,1/16W,CHIP,GA G21796-017               R6P46           
RES_0402-100.0,1%,1/16W,CHIP,GA G21796-017               R6T8            
RES_0402-100.0,1%,1/16W,CHIP,GA G21796-017               R6T9            
RES_0402-100.0,1%,1/16W,CHIP,GA G21796-017               R7A13           
RES_0402-100.0,1%,1/16W,CHIP,GA G21796-017               R7D32           
RES_0402-100.0,1%,1/16W,CHIP,GA G21796-017               R7P19           
RES_0402-100.0,1%,1/16W,CHIP,GA G21796-017               R7P30           
RES_0402-100.0,1%,1/16W,CHIP,GA G21796-017               R8C21           
RES_0402-100.0,1%,1/16W,CHIP,GA G21796-017               R8C26           
RES_0402-100.0,1%,1/16W,CHIP,GA G21796-017               R8D42           
RES_0402-100.0,1%,1/16W,CHIP,GA G21796-017               R9A9            
RES_0402-100.0,1%,1/16W,CHIP,GA G21796-017               R9B7            
RES_0402-100.0,1%,1/16W,CHIP,GA G21796-017               R9F25           
RES_0402-100.0,1%,1/16W,CHIP,GA G21796-017               R9N2            
RES_0402-100.0,1%,1/16W,CHIP,GA G21796-017               R9P1            
RES_0402-100.0,1%,1/16W,CHIP,GA G21796-017               R9T7            
RES_0402-100.0,1%,1/16W,CHIP,GA G21796-017               R9U3            

----------------

RES_0402-100.0,1%,1/16W,EMPTY,A G21796-017               R1D28           
RES_0402-100.0,1%,1/16W,EMPTY,A G21796-017               R3L11           
RES_0402-100.0,1%,1/16W,EMPTY,A G21796-017               R3P13           
RES_0402-100.0,1%,1/16W,EMPTY,A G21796-017               R4L2            
RES_0402-100.0,1%,1/16W,EMPTY,A G21796-017               R4U6            
RES_0402-100.0,1%,1/16W,EMPTY,A G21796-017               R6P35           
RES_0402-100.0,1%,1/16W,EMPTY,A G21796-017               R7L2            
RES_0402-100.0,1%,1/16W,EMPTY,A G21796-017               R7U2            
RES_0402-100.0,1%,1/16W,EMPTY,A G21796-017               R8B15           
RES_0402-100.0,1%,1/16W,EMPTY,A G21796-017               R9M7            

----------------

RES_0402-100.0K,1%,1/16W,CHIP,A G21796-010               R1D11           
RES_0402-100.0K,1%,1/16W,CHIP,A G21796-010               R1D15           
RES_0402-100.0K,1%,1/16W,CHIP,A G21796-010               R1D18           
RES_0402-100.0K,1%,1/16W,CHIP,A G21796-010               R1D32           
RES_0402-100.0K,1%,1/16W,CHIP,A G21796-010               R1D37           
RES_0402-100.0K,1%,1/16W,CHIP,A G21796-010               R1D39           
RES_0402-100.0K,1%,1/16W,CHIP,A G21796-010               R1L9            
RES_0402-100.0K,1%,1/16W,CHIP,A G21796-010               R1U1            
RES_0402-100.0K,1%,1/16W,CHIP,A G21796-010               R1U2            
RES_0402-100.0K,1%,1/16W,CHIP,A G21796-010               R1U4            
RES_0402-100.0K,1%,1/16W,CHIP,A G21796-010               R1U5            
RES_0402-100.0K,1%,1/16W,CHIP,A G21796-010               R2T15           
RES_0402-100.0K,1%,1/16W,CHIP,A G21796-010               R3M8            
RES_0402-100.0K,1%,1/16W,CHIP,A G21796-010               R3M9            
RES_0402-100.0K,1%,1/16W,CHIP,A G21796-010               R8B4            
RES_0402-100.0K,1%,1/16W,CHIP,A G21796-010               R8D38           
RES_0402-100.0K,1%,1/16W,CHIP,A G21796-010               R9F4            
RES_0402-100.0K,1%,1/16W,CHIP,A G21796-010               R9F42           
RES_0402-100.0K,1%,1/16W,CHIP,A G21796-010               R9F43           
RES_0402-100.0K,1%,1/16W,CHIP,A G21796-010               R9F44           
RES_0402-100.0K,1%,1/16W,CHIP,A G21796-010               R9F45           
RES_0402-100.0K,1%,1/16W,CHIP,A G21796-010               R9F46           
RES_0402-100.0K,1%,1/16W,CHIP,A G21796-010               R9G26           
RES_0402-100.0K,1%,1/16W,CHIP,A G21796-010               R9P23           
RES_0402-100.0K,1%,1/16W,CHIP,A G21796-010               R9P28           
RES_0402-100.0K,1%,1/16W,CHIP,A G21796-010               R9P29           
RES_0402-100.0K,1%,1/16W,CHIP,A G21796-010               R9P33           

----------------

RES_0402-100.0K,1%,1/16W,CHIP,B G21796-160               R1C13           
RES_0402-100.0K,1%,1/16W,CHIP,B G21796-160               R3L12           
RES_0402-100.0K,1%,1/16W,CHIP,B G21796-160               R3P12           
RES_0402-100.0K,1%,1/16W,CHIP,B G21796-160               R4D27           
RES_0402-100.0K,1%,1/16W,CHIP,B G21796-160               R4D60           
RES_0402-100.0K,1%,1/16W,CHIP,B G21796-160               R7F34           
RES_0402-100.0K,1%,1/16W,CHIP,B G21796-160               R8A4            
RES_0402-100.0K,1%,1/16W,CHIP,B G21796-160               R9M8            
RES_0402-100.0K,1%,1/16W,CHIP,B G21796-160               R9U11           

----------------

RES_0402-100.0K,1%,1/16W,EMPTYA G21796-010               R2L25           
RES_0402-100.0K,1%,1/16W,EMPTYA G21796-010               R2L26           
RES_0402-100.0K,1%,1/16W,EMPTYA G21796-010               R3M5            
RES_0402-100.0K,1%,1/16W,EMPTYA G21796-010               R3P21           
RES_0402-100.0K,1%,1/16W,EMPTYA G21796-010               R6P40           
RES_0402-100.0K,1%,1/16W,EMPTYA G21796-010               R7F20           
RES_0402-100.0K,1%,1/16W,EMPTYA G21796-010               R8A7            
RES_0402-100.0K,1%,1/16W,EMPTYA G21796-010               R8E40           
RES_0402-100.0K,1%,1/16W,EMPTYA G21796-010               R9M5            
RES_0402-100.0K,1%,1/16W,EMPTYA G21796-010               R9U8            

----------------

RES_0402-105.0K,1%,1/16W,CHIP,A G21796-099               R1D14           

----------------

RES_0402-110,1%,1/16W,EMPTY,G2A G21796-203               R6P33           

----------------

RES_0402-113,1%,1/16W,CHIP,G21A G21796-341               R8B9            

----------------

RES_0402-11K,1%,1/16W,CHIP,G21A G21796-220               R1D42           

----------------

RES_0402-12.1K,1%,1/16W,CHIP,GA G21796-089               R9P24           

----------------

RES_0402-12K,1%,1/16W,CHIP,G21A G21796-264               R9F31           

----------------

RES_0402-13K,1.0%,1/16W,CHIP,GA G21796-221               R9F32           

----------------

RES_0402-15.0K,1%,1/16W,CHIP,GA G21796-107               R9P18           
RES_0402-15.0K,1%,1/16W,CHIP,GA G21796-107               R9T6            

----------------

RES_0402-150.0,1%,1/16W,CHIP,GA G21796-009               R1B8            
RES_0402-150.0,1%,1/16W,CHIP,GA G21796-009               R1D9            
RES_0402-150.0,1%,1/16W,CHIP,GA G21796-009               R1G7            
RES_0402-150.0,1%,1/16W,CHIP,GA G21796-009               R1L15           
RES_0402-150.0,1%,1/16W,CHIP,GA G21796-009               R1L17           
RES_0402-150.0,1%,1/16W,CHIP,GA G21796-009               R1U35           
RES_0402-150.0,1%,1/16W,CHIP,GA G21796-009               R1U41           
RES_0402-150.0,1%,1/16W,CHIP,GA G21796-009               R2T72           
RES_0402-150.0,1%,1/16W,CHIP,GA G21796-009               R2T73           
RES_0402-150.0,1%,1/16W,CHIP,GA G21796-009               R2U40           
RES_0402-150.0,1%,1/16W,CHIP,GA G21796-009               R2U41           
RES_0402-150.0,1%,1/16W,CHIP,GA G21796-009               R3P15           
RES_0402-150.0,1%,1/16W,CHIP,GA G21796-009               R4D51           
RES_0402-150.0,1%,1/16W,CHIP,GA G21796-009               R4E6            
RES_0402-150.0,1%,1/16W,CHIP,GA G21796-009               R4P17           
RES_0402-150.0,1%,1/16W,CHIP,GA G21796-009               R4P20           
RES_0402-150.0,1%,1/16W,CHIP,GA G21796-009               R4P23           
RES_0402-150.0,1%,1/16W,CHIP,GA G21796-009               R4P24           
RES_0402-150.0,1%,1/16W,CHIP,GA G21796-009               R4R2            
RES_0402-150.0,1%,1/16W,CHIP,GA G21796-009               R4R3            
RES_0402-150.0,1%,1/16W,CHIP,GA G21796-009               R4R4            
RES_0402-150.0,1%,1/16W,CHIP,GA G21796-009               R6D9            
RES_0402-150.0,1%,1/16W,CHIP,GA G21796-009               R6T6            
RES_0402-150.0,1%,1/16W,CHIP,GA G21796-009               R6T7            
RES_0402-150.0,1%,1/16W,CHIP,GA G21796-009               R7A17           
RES_0402-150.0,1%,1/16W,CHIP,GA G21796-009               R7G24           
RES_0402-150.0,1%,1/16W,CHIP,GA G21796-009               R7P5            
RES_0402-150.0,1%,1/16W,CHIP,GA G21796-009               R7P18           
RES_0402-150.0,1%,1/16W,CHIP,GA G21796-009               R7P20           
RES_0402-150.0,1%,1/16W,CHIP,GA G21796-009               R7P21           
RES_0402-150.0,1%,1/16W,CHIP,GA G21796-009               R7P27           
RES_0402-150.0,1%,1/16W,CHIP,GA G21796-009               R7P28           
RES_0402-150.0,1%,1/16W,CHIP,GA G21796-009               R8A13           
RES_0402-150.0,1%,1/16W,CHIP,GA G21796-009               R8A14           
RES_0402-150.0,1%,1/16W,CHIP,GA G21796-009               R9A11           
RES_0402-150.0,1%,1/16W,CHIP,GA G21796-009               R9G1            
RES_0402-150.0,1%,1/16W,CHIP,GA G21796-009               R9G2            
RES_0402-150.0,1%,1/16W,CHIP,GA G21796-009               R9G3            

----------------

RES_0402-150.0K,1%,1/16W,CHIP,A G21796-109               R1D20           
RES_0402-150.0K,1%,1/16W,CHIP,A G21796-109               R9P17           

----------------

RES_0402-169,1.0%,1/16W,CHIP,GA G21796-276               R3N1            

----------------

RES_0402-16K,1.0%,1/16W,CHIP,GA G21796-317               R1D34           
RES_0402-16K,1.0%,1/16W,CHIP,GA G21796-317               R3N29           

----------------

RES_0402-2,1.0%,1/16W,CHIP,G21A G21796-274               R1F4            
RES_0402-2,1.0%,1/16W,CHIP,G21A G21796-274               R1G1            
RES_0402-2,1.0%,1/16W,CHIP,G21A G21796-274               R1G14           
RES_0402-2,1.0%,1/16W,CHIP,G21A G21796-274               R4F3            
RES_0402-2,1.0%,1/16W,CHIP,G21A G21796-274               R4G1            
RES_0402-2,1.0%,1/16W,CHIP,G21A G21796-274               R4G20           
RES_0402-2,1.0%,1/16W,CHIP,G21A G21796-274               R6L3            
RES_0402-2,1.0%,1/16W,CHIP,G21A G21796-274               R6L14           
RES_0402-2,1.0%,1/16W,CHIP,G21A G21796-274               R6M2            
RES_0402-2,1.0%,1/16W,CHIP,G21A G21796-274               R9L3            
RES_0402-2,1.0%,1/16W,CHIP,G21A G21796-274               R9L8            
RES_0402-2,1.0%,1/16W,CHIP,G21A G21796-274               R9M2            

----------------

RES_0402-2.0K,1%,1/16W,CHIP,G2A G21796-001               R1L1            
RES_0402-2.0K,1%,1/16W,CHIP,G2A G21796-001               R2L4            
RES_0402-2.0K,1%,1/16W,CHIP,G2A G21796-001               R2L5            
RES_0402-2.0K,1%,1/16W,CHIP,G2A G21796-001               R2L6            
RES_0402-2.0K,1%,1/16W,CHIP,G2A G21796-001               R2L11           
RES_0402-2.0K,1%,1/16W,CHIP,G2A G21796-001               R2L12           
RES_0402-2.0K,1%,1/16W,CHIP,G2A G21796-001               R2L15           
RES_0402-2.0K,1%,1/16W,CHIP,G2A G21796-001               R2L21           
RES_0402-2.0K,1%,1/16W,CHIP,G2A G21796-001               R2L23           
RES_0402-2.0K,1%,1/16W,CHIP,G2A G21796-001               R3N3            
RES_0402-2.0K,1%,1/16W,CHIP,G2A G21796-001               R8C15           
RES_0402-2.0K,1%,1/16W,CHIP,G2A G21796-001               R8C16           
RES_0402-2.0K,1%,1/16W,CHIP,G2A G21796-001               R9M16           
RES_0402-2.0K,1%,1/16W,CHIP,G2A G21796-001               R9M17           

----------------

RES_0402-2.0K,1%,1/16W,EMPTY,GA G21796-001               R6P32           
RES_0402-2.0K,1%,1/16W,EMPTY,GA G21796-001               R6P37           

----------------

RES_0402-2.2,5%,1/16W,EMPTY,G2A G21497-016               R4A7            
RES_0402-2.2,5%,1/16W,EMPTY,G2A G21497-016               R4F6            
RES_0402-2.2,5%,1/16W,EMPTY,G2A G21497-016               R7A15           
RES_0402-2.2,5%,1/16W,EMPTY,G2A G21497-016               R7F7            
RES_0402-2.2,5%,1/16W,EMPTY,G2A G21497-016               R8F3            

----------------

RES_0402-2.21K,1%,1/16W,CHIP,GA G21796-112               R1R16           
RES_0402-2.21K,1%,1/16W,CHIP,GA G21796-112               R1R17           
RES_0402-2.21K,1%,1/16W,CHIP,GA G21796-112               R1R18           
RES_0402-2.21K,1%,1/16W,CHIP,GA G21796-112               R1R19           
RES_0402-2.21K,1%,1/16W,CHIP,GA G21796-112               R1R20           
RES_0402-2.21K,1%,1/16W,CHIP,GA G21796-112               R1R21           
RES_0402-2.21K,1%,1/16W,CHIP,GA G21796-112               R1R22           
RES_0402-2.21K,1%,1/16W,CHIP,GA G21796-112               R1R23           
RES_0402-2.21K,1%,1/16W,CHIP,GA G21796-112               R2T29           
RES_0402-2.21K,1%,1/16W,CHIP,GA G21796-112               R4U2            
RES_0402-2.21K,1%,1/16W,CHIP,GA G21796-112               R8F23           
RES_0402-2.21K,1%,1/16W,CHIP,GA G21796-112               R9A7            
RES_0402-2.21K,1%,1/16W,CHIP,GA G21796-112               R9A12           
RES_0402-2.21K,1%,1/16W,CHIP,GA G21796-112               R9A16           

----------------

RES_0402-2.26K,1.0%,1/16W,CHIPA G21796-311               R1D7            
RES_0402-2.26K,1.0%,1/16W,CHIPA G21796-311               R2U5            
RES_0402-2.26K,1.0%,1/16W,CHIPA G21796-311               R2U13           
RES_0402-2.26K,1.0%,1/16W,CHIPA G21796-311               R3P61           
RES_0402-2.26K,1.0%,1/16W,CHIPA G21796-311               R4E4            
RES_0402-2.26K,1.0%,1/16W,CHIPA G21796-311               R7D5            
RES_0402-2.26K,1.0%,1/16W,CHIPA G21796-311               R7D9            

----------------

RES_0402-2.26K,1.0%,1/16W,EMPTA G21796-311               R1B13           
RES_0402-2.26K,1.0%,1/16W,EMPTA G21796-311               R1C18           
RES_0402-2.26K,1.0%,1/16W,EMPTA G21796-311               R1D53           
RES_0402-2.26K,1.0%,1/16W,EMPTA G21796-311               R1G6            
RES_0402-2.26K,1.0%,1/16W,EMPTA G21796-311               R2L24           
RES_0402-2.26K,1.0%,1/16W,EMPTA G21796-311               R3N23           
RES_0402-2.26K,1.0%,1/16W,EMPTA G21796-311               R4D31           
RES_0402-2.26K,1.0%,1/16W,EMPTA G21796-311               R4E20           
RES_0402-2.26K,1.0%,1/16W,EMPTA G21796-311               R6P49           
RES_0402-2.26K,1.0%,1/16W,EMPTA G21796-311               R7A9            
RES_0402-2.26K,1.0%,1/16W,EMPTA G21796-311               R7F36           
RES_0402-2.26K,1.0%,1/16W,EMPTA G21796-311               R8G3            
RES_0402-2.26K,1.0%,1/16W,EMPTA G21796-311               R8G6            

----------------

RES_0402-2.67K,1%,1/16W,CHIP,GA G21796-180               R8A2            

----------------

RES_0402-2.7K,1%,1/16W,CHIP,G2A G21796-344               R1T4            
RES_0402-2.7K,1%,1/16W,CHIP,G2A G21796-344               R1U21           
RES_0402-2.7K,1%,1/16W,CHIP,G2A G21796-344               R1U22           
RES_0402-2.7K,1%,1/16W,CHIP,G2A G21796-344               R1U49           
RES_0402-2.7K,1%,1/16W,CHIP,G2A G21796-344               R9G8            
RES_0402-2.7K,1%,1/16W,CHIP,G2A G21796-344               R9G35           
RES_0402-2.7K,1%,1/16W,CHIP,G2A G21796-344               R9P4            
RES_0402-2.7K,1%,1/16W,CHIP,G2A G21796-344               R9P20           

----------------

RES_0402-2.7K,1%,1/16W,EMPTY,GA G21796-344               R1T5            
RES_0402-2.7K,1%,1/16W,EMPTY,GA G21796-344               R1T6            
RES_0402-2.7K,1%,1/16W,EMPTY,GA G21796-344               R1U23           
RES_0402-2.7K,1%,1/16W,EMPTY,GA G21796-344               R1U24           
RES_0402-2.7K,1%,1/16W,EMPTY,GA G21796-344               R2N17           

----------------

RES_0402-20.0,1%,1/16W,CHIP,G2A G21796-173               R1B6            
RES_0402-20.0,1%,1/16W,CHIP,G2A G21796-173               R1B7            
RES_0402-20.0,1%,1/16W,CHIP,G2A G21796-173               R1M8            
RES_0402-20.0,1%,1/16W,CHIP,G2A G21796-173               R1M9            
RES_0402-20.0,1%,1/16W,CHIP,G2A G21796-173               R1T7            
RES_0402-20.0,1%,1/16W,CHIP,G2A G21796-173               R1T8            
RES_0402-20.0,1%,1/16W,CHIP,G2A G21796-173               R1U9            
RES_0402-20.0,1%,1/16W,CHIP,G2A G21796-173               R1U10           
RES_0402-20.0,1%,1/16W,CHIP,G2A G21796-173               R1U19           
RES_0402-20.0,1%,1/16W,CHIP,G2A G21796-173               R1U20           
RES_0402-20.0,1%,1/16W,CHIP,G2A G21796-173               R1U25           
RES_0402-20.0,1%,1/16W,CHIP,G2A G21796-173               R1U31           
RES_0402-20.0,1%,1/16W,CHIP,G2A G21796-173               R2T49           
RES_0402-20.0,1%,1/16W,CHIP,G2A G21796-173               R2T55           
RES_0402-20.0,1%,1/16W,CHIP,G2A G21796-173               R2T56           
RES_0402-20.0,1%,1/16W,CHIP,G2A G21796-173               R2U1            
RES_0402-20.0,1%,1/16W,CHIP,G2A G21796-173               R2U6            
RES_0402-20.0,1%,1/16W,CHIP,G2A G21796-173               R2U7            
RES_0402-20.0,1%,1/16W,CHIP,G2A G21796-173               R2U9            
RES_0402-20.0,1%,1/16W,CHIP,G2A G21796-173               R2U10           
RES_0402-20.0,1%,1/16W,CHIP,G2A G21796-173               R2U31           
RES_0402-20.0,1%,1/16W,CHIP,G2A G21796-173               R2U32           
RES_0402-20.0,1%,1/16W,CHIP,G2A G21796-173               R2U33           
RES_0402-20.0,1%,1/16W,CHIP,G2A G21796-173               R2U34           
RES_0402-20.0,1%,1/16W,CHIP,G2A G21796-173               R3P23           
RES_0402-20.0,1%,1/16W,CHIP,G2A G21796-173               R3P24           
RES_0402-20.0,1%,1/16W,CHIP,G2A G21796-173               R3R8            
RES_0402-20.0,1%,1/16W,CHIP,G2A G21796-173               R3R9            
RES_0402-20.0,1%,1/16W,CHIP,G2A G21796-173               R4D43           
RES_0402-20.0,1%,1/16W,CHIP,G2A G21796-173               R4D44           
RES_0402-20.0,1%,1/16W,CHIP,G2A G21796-173               R4T9            
RES_0402-20.0,1%,1/16W,CHIP,G2A G21796-173               R4T10           
RES_0402-20.0,1%,1/16W,CHIP,G2A G21796-173               R6U13           
RES_0402-20.0,1%,1/16W,CHIP,G2A G21796-173               R6U14           
RES_0402-20.0,1%,1/16W,CHIP,G2A G21796-173               R7B2            
RES_0402-20.0,1%,1/16W,CHIP,G2A G21796-173               R7B3            
RES_0402-20.0,1%,1/16W,CHIP,G2A G21796-173               R7F25           
RES_0402-20.0,1%,1/16W,CHIP,G2A G21796-173               R7F26           
RES_0402-20.0,1%,1/16W,CHIP,G2A G21796-173               R7M4            
RES_0402-20.0,1%,1/16W,CHIP,G2A G21796-173               R7M5            
RES_0402-20.0,1%,1/16W,CHIP,G2A G21796-173               R8A8            
RES_0402-20.0,1%,1/16W,CHIP,G2A G21796-173               R8A9            
RES_0402-20.0,1%,1/16W,CHIP,G2A G21796-173               R8B27           
RES_0402-20.0,1%,1/16W,CHIP,G2A G21796-173               R8B28           
RES_0402-20.0,1%,1/16W,CHIP,G2A G21796-173               R8C11           
RES_0402-20.0,1%,1/16W,CHIP,G2A G21796-173               R8C12           
RES_0402-20.0,1%,1/16W,CHIP,G2A G21796-173               R8C14           
RES_0402-20.0,1%,1/16W,CHIP,G2A G21796-173               R8C20           
RES_0402-20.0,1%,1/16W,CHIP,G2A G21796-173               R8D3            
RES_0402-20.0,1%,1/16W,CHIP,G2A G21796-173               R8D4            
RES_0402-20.0,1%,1/16W,CHIP,G2A G21796-173               R8D6            
RES_0402-20.0,1%,1/16W,CHIP,G2A G21796-173               R8D7            
RES_0402-20.0,1%,1/16W,CHIP,G2A G21796-173               R8D23           
RES_0402-20.0,1%,1/16W,CHIP,G2A G21796-173               R8D24           
RES_0402-20.0,1%,1/16W,CHIP,G2A G21796-173               R8G4            
RES_0402-20.0,1%,1/16W,CHIP,G2A G21796-173               R8G5            
RES_0402-20.0,1%,1/16W,CHIP,G2A G21796-173               R9F22           
RES_0402-20.0,1%,1/16W,CHIP,G2A G21796-173               R9F23           
RES_0402-20.0,1%,1/16W,CHIP,G2A G21796-173               R9G12           
RES_0402-20.0,1%,1/16W,CHIP,G2A G21796-173               R9G13           
RES_0402-20.0,1%,1/16W,CHIP,G2A G21796-173               R9G14           
RES_0402-20.0,1%,1/16W,CHIP,G2A G21796-173               R9G15           
RES_0402-20.0,1%,1/16W,CHIP,G2A G21796-173               R9M12           
RES_0402-20.0,1%,1/16W,CHIP,G2A G21796-173               R9M13           
RES_0402-20.0,1%,1/16W,CHIP,G2A G21796-173               R9M14           
RES_0402-20.0,1%,1/16W,CHIP,G2A G21796-173               R9M15           
RES_0402-20.0,1%,1/16W,CHIP,G2A G21796-173               R9R7            
RES_0402-20.0,1%,1/16W,CHIP,G2A G21796-173               R9R8            

----------------

RES_0402-20.0,1%,1/16W,EMPTY,GA G21796-173               R2U8            
RES_0402-20.0,1%,1/16W,EMPTY,GA G21796-173               R2U12           
RES_0402-20.0,1%,1/16W,EMPTY,GA G21796-173               R2U35           
RES_0402-20.0,1%,1/16W,EMPTY,GA G21796-173               R2U36           

----------------

RES_0402-20.0K,1%,1/16W,CHIP,GA G21796-040               R1R7            
RES_0402-20.0K,1%,1/16W,CHIP,GA G21796-040               R3N4            
RES_0402-20.0K,1%,1/16W,CHIP,GA G21796-040               R4B5            
RES_0402-20.0K,1%,1/16W,CHIP,GA G21796-040               R4G7            
RES_0402-20.0K,1%,1/16W,CHIP,GA G21796-040               R7B15           
RES_0402-20.0K,1%,1/16W,CHIP,GA G21796-040               R7C10           
RES_0402-20.0K,1%,1/16W,CHIP,GA G21796-040               R7F13           
RES_0402-20.0K,1%,1/16W,CHIP,GA G21796-040               R8E16           
RES_0402-20.0K,1%,1/16W,CHIP,GA G21796-040               R9A5            

----------------

RES_0402-20.0K,1%,1/16W,EMPTY,A G21796-040               R9A6            

----------------

RES_0402-200.0,1%,1/16W,CHIP,GA G21796-004               R1L22           
RES_0402-200.0,1%,1/16W,CHIP,GA G21796-004               R1L31           
RES_0402-200.0,1%,1/16W,CHIP,GA G21796-004               R1M14           
RES_0402-200.0,1%,1/16W,CHIP,GA G21796-004               R2R9            
RES_0402-200.0,1%,1/16W,CHIP,GA G21796-004               R2T13           
RES_0402-200.0,1%,1/16W,CHIP,GA G21796-004               R2T19           
RES_0402-200.0,1%,1/16W,CHIP,GA G21796-004               R2T26           
RES_0402-200.0,1%,1/16W,CHIP,GA G21796-004               R2T37           
RES_0402-200.0,1%,1/16W,CHIP,GA G21796-004               R9E10           
RES_0402-200.0,1%,1/16W,CHIP,GA G21796-004               R9E11           
RES_0402-200.0,1%,1/16W,CHIP,GA G21796-004               R9E12           

----------------

RES_0402-200.0K,1%,1/16W,CHIP,A G21796-080               R1U50           

----------------

RES_0402-22.1,1.0%,1/16W,CHIP,A G21796-250               R1B5            
RES_0402-22.1,1.0%,1/16W,CHIP,A G21796-250               R1C30           
RES_0402-22.1,1.0%,1/16W,CHIP,A G21796-250               R1G12           
RES_0402-22.1,1.0%,1/16W,CHIP,A G21796-250               R1T9            
RES_0402-22.1,1.0%,1/16W,CHIP,A G21796-250               R1T26           
RES_0402-22.1,1.0%,1/16W,CHIP,A G21796-250               R1T28           
RES_0402-22.1,1.0%,1/16W,CHIP,A G21796-250               R2L16           
RES_0402-22.1,1.0%,1/16W,CHIP,A G21796-250               R2T41           
RES_0402-22.1,1.0%,1/16W,CHIP,A G21796-250               R2T42           
RES_0402-22.1,1.0%,1/16W,CHIP,A G21796-250               R2T45           
RES_0402-22.1,1.0%,1/16W,CHIP,A G21796-250               R2T46           
RES_0402-22.1,1.0%,1/16W,CHIP,A G21796-250               R3M3            
RES_0402-22.1,1.0%,1/16W,CHIP,A G21796-250               R3P20           
RES_0402-22.1,1.0%,1/16W,CHIP,A G21796-250               R4B7            
RES_0402-22.1,1.0%,1/16W,CHIP,A G21796-250               R4D46           
RES_0402-22.1,1.0%,1/16W,CHIP,A G21796-250               R4D63           
RES_0402-22.1,1.0%,1/16W,CHIP,A G21796-250               R4G12           
RES_0402-22.1,1.0%,1/16W,CHIP,A G21796-250               R7B12           
RES_0402-22.1,1.0%,1/16W,CHIP,A G21796-250               R7E15           
RES_0402-22.1,1.0%,1/16W,CHIP,A G21796-250               R7F16           
RES_0402-22.1,1.0%,1/16W,CHIP,A G21796-250               R7F24           
RES_0402-22.1,1.0%,1/16W,CHIP,A G21796-250               R8A11           
RES_0402-22.1,1.0%,1/16W,CHIP,A G21796-250               R8E7            
RES_0402-22.1,1.0%,1/16W,CHIP,A G21796-250               R8F10           
RES_0402-22.1,1.0%,1/16W,CHIP,A G21796-250               R8F27           
RES_0402-22.1,1.0%,1/16W,CHIP,A G21796-250               R8F28           
RES_0402-22.1,1.0%,1/16W,CHIP,A G21796-250               R8F30           
RES_0402-22.1,1.0%,1/16W,CHIP,A G21796-250               R8F31           
RES_0402-22.1,1.0%,1/16W,CHIP,A G21796-250               R8F33           
RES_0402-22.1,1.0%,1/16W,CHIP,A G21796-250               R9E17           
RES_0402-22.1,1.0%,1/16W,CHIP,A G21796-250               R9E19           
RES_0402-22.1,1.0%,1/16W,CHIP,A G21796-250               R9F1            
RES_0402-22.1,1.0%,1/16W,CHIP,A G21796-250               R9F11           

----------------

RES_0402-221,1.0%,1/16W,CHIP,GA G21796-271               R1C1            
RES_0402-221,1.0%,1/16W,CHIP,GA G21796-271               R1L33           
RES_0402-221,1.0%,1/16W,CHIP,GA G21796-271               R2U42           
RES_0402-221,1.0%,1/16W,CHIP,GA G21796-271               R2U44           
RES_0402-221,1.0%,1/16W,CHIP,GA G21796-271               R3B1            
RES_0402-221,1.0%,1/16W,CHIP,GA G21796-271               R6B3            
RES_0402-221,1.0%,1/16W,CHIP,GA G21796-271               R6N10           
RES_0402-221,1.0%,1/16W,CHIP,GA G21796-271               R9A20           
RES_0402-221,1.0%,1/16W,CHIP,GA G21796-271               R9E24           
RES_0402-221,1.0%,1/16W,CHIP,GA G21796-271               R9F28           

----------------

RES_0402-23.2K,1%,1/16W,CHIP,GA G21796-114               R8E31           

----------------

RES_0402-24.9K,1%,1/16W,CHIP,GA G21796-254               R8E39           

----------------

RES_0402-240,1.0%,1/16W,CHIP,GA G21796-294               R1T27           
RES_0402-240,1.0%,1/16W,CHIP,GA G21796-294               R3D12           
RES_0402-240,1.0%,1/16W,CHIP,GA G21796-294               R3D24           
RES_0402-240,1.0%,1/16W,CHIP,GA G21796-294               R3P60           
RES_0402-240,1.0%,1/16W,CHIP,GA G21796-294               R3R13           
RES_0402-240,1.0%,1/16W,CHIP,GA G21796-294               R4C10           
RES_0402-240,1.0%,1/16W,CHIP,GA G21796-294               R4P14           
RES_0402-240,1.0%,1/16W,CHIP,GA G21796-294               R4P21           
RES_0402-240,1.0%,1/16W,CHIP,GA G21796-294               R4T5            
RES_0402-240,1.0%,1/16W,CHIP,GA G21796-294               R4T6            
RES_0402-240,1.0%,1/16W,CHIP,GA G21796-294               R5D3            
RES_0402-240,1.0%,1/16W,CHIP,GA G21796-294               R6D6            
RES_0402-240,1.0%,1/16W,CHIP,GA G21796-294               R6T1            
RES_0402-240,1.0%,1/16W,CHIP,GA G21796-294               R6T2            
RES_0402-240,1.0%,1/16W,CHIP,GA G21796-294               R7M2            
RES_0402-240,1.0%,1/16W,CHIP,GA G21796-294               R7M7            
RES_0402-240,1.0%,1/16W,CHIP,GA G21796-294               R7P14           
RES_0402-240,1.0%,1/16W,CHIP,GA G21796-294               R9M18           
RES_0402-240,1.0%,1/16W,CHIP,GA G21796-294               R9M19           

----------------

RES_0402-240,1.0%,1/16W,EMPTY,A G21796-294               R3D13           
RES_0402-240,1.0%,1/16W,EMPTY,A G21796-294               R3D16           
RES_0402-240,1.0%,1/16W,EMPTY,A G21796-294               R3D17           
RES_0402-240,1.0%,1/16W,EMPTY,A G21796-294               R3D22           
RES_0402-240,1.0%,1/16W,EMPTY,A G21796-294               R3D23           
RES_0402-240,1.0%,1/16W,EMPTY,A G21796-294               R3D25           
RES_0402-240,1.0%,1/16W,EMPTY,A G21796-294               R3D26           
RES_0402-240,1.0%,1/16W,EMPTY,A G21796-294               R4P1            
RES_0402-240,1.0%,1/16W,EMPTY,A G21796-294               R4P6            
RES_0402-240,1.0%,1/16W,EMPTY,A G21796-294               R4P7            
RES_0402-240,1.0%,1/16W,EMPTY,A G21796-294               R5D4            
RES_0402-240,1.0%,1/16W,EMPTY,A G21796-294               R6D7            
RES_0402-240,1.0%,1/16W,EMPTY,A G21796-294               R6D10           
RES_0402-240,1.0%,1/16W,EMPTY,A G21796-294               R6D13           
RES_0402-240,1.0%,1/16W,EMPTY,A G21796-294               R6D14           
RES_0402-240,1.0%,1/16W,EMPTY,A G21796-294               R6D15           
RES_0402-240,1.0%,1/16W,EMPTY,A G21796-294               R7P15           
RES_0402-240,1.0%,1/16W,EMPTY,A G21796-294               R7P22           

----------------

RES_0402-249,0.1%,1/16W,CHIP,GA G85996-031               R3D27           
RES_0402-249,0.1%,1/16W,CHIP,GA G85996-031               R5D5            

----------------

RES_0402-249K,1.0%,1/16W,CHIP,A G21796-189               R9P7            

----------------

RES_0402-27.4,1%,1/16W,CHIP,G2A G21796-182               R4D1            
RES_0402-27.4,1%,1/16W,CHIP,G2A G21796-182               R4D2            
RES_0402-27.4,1%,1/16W,CHIP,G2A G21796-182               R4D3            
RES_0402-27.4,1%,1/16W,CHIP,G2A G21796-182               R4D4            
RES_0402-27.4,1%,1/16W,CHIP,G2A G21796-182               R4D5            
RES_0402-27.4,1%,1/16W,CHIP,G2A G21796-182               R4D6            
RES_0402-27.4,1%,1/16W,CHIP,G2A G21796-182               R4D7            
RES_0402-27.4,1%,1/16W,CHIP,G2A G21796-182               R4D8            
RES_0402-27.4,1%,1/16W,CHIP,G2A G21796-182               R4D9            
RES_0402-27.4,1%,1/16W,CHIP,G2A G21796-182               R4D10           
RES_0402-27.4,1%,1/16W,CHIP,G2A G21796-182               R4D11           
RES_0402-27.4,1%,1/16W,CHIP,G2A G21796-182               R4D12           
RES_0402-27.4,1%,1/16W,CHIP,G2A G21796-182               R4D13           
RES_0402-27.4,1%,1/16W,CHIP,G2A G21796-182               R4D14           
RES_0402-27.4,1%,1/16W,CHIP,G2A G21796-182               R4D16           
RES_0402-27.4,1%,1/16W,CHIP,G2A G21796-182               R4D17           
RES_0402-27.4,1%,1/16W,CHIP,G2A G21796-182               R4D19           
RES_0402-27.4,1%,1/16W,CHIP,G2A G21796-182               R4D20           
RES_0402-27.4,1%,1/16W,CHIP,G2A G21796-182               R4D21           
RES_0402-27.4,1%,1/16W,CHIP,G2A G21796-182               R4D22           
RES_0402-27.4,1%,1/16W,CHIP,G2A G21796-182               R4D23           
RES_0402-27.4,1%,1/16W,CHIP,G2A G21796-182               R4D25           
RES_0402-27.4,1%,1/16W,CHIP,G2A G21796-182               R4D28           
RES_0402-27.4,1%,1/16W,CHIP,G2A G21796-182               R4D29           

----------------

RES_0402-274K,1.0%,1/16W,CHIP,A G21796-331               R9P13           

----------------

RES_0402-3.16K,1%,1/16W,CHIP,GA G21796-043               R1B12           
RES_0402-3.16K,1%,1/16W,CHIP,GA G21796-043               R3N31           
RES_0402-3.16K,1%,1/16W,CHIP,GA G21796-043               R4C11           
RES_0402-3.16K,1%,1/16W,CHIP,GA G21796-043               R4D64           
RES_0402-3.16K,1%,1/16W,CHIP,GA G21796-043               R4E2            
RES_0402-3.16K,1%,1/16W,CHIP,GA G21796-043               R7A10           
RES_0402-3.16K,1%,1/16W,CHIP,GA G21796-043               R9N7            

----------------

RES_0402-3.32K,1%,1/16W,CHIP,GA G21796-027               R1R3            
RES_0402-3.32K,1%,1/16W,CHIP,GA G21796-027               R1R9            
RES_0402-3.32K,1%,1/16W,CHIP,GA G21796-027               R9E7            
RES_0402-3.32K,1%,1/16W,CHIP,GA G21796-027               R9F5            

----------------

RES_0402-3.32K,1%,1/16W,EMPTY,A G21796-027               R1C35           
RES_0402-3.32K,1%,1/16W,EMPTY,A G21796-027               R1R6            
RES_0402-3.32K,1%,1/16W,EMPTY,A G21796-027               R3P54           

----------------

RES_0402-3.3K,5%,1/16W,CHIP,G2A G21497-013               R8B24           
RES_0402-3.3K,5%,1/16W,CHIP,G2A G21497-013               R8B26           

----------------

RES_0402-3.48K,1.0%,1/16W,CHIPA G21796-279               R1U28           
RES_0402-3.48K,1.0%,1/16W,CHIPA G21796-279               R1U44           

----------------

RES_0402-3.74K,1%,1/16W,CHIP,GA G21796-059               R8D40           

----------------

RES_0402-301.0,1%,1/16W,CHIP,GA G21796-076               R1L37           

----------------

RES_0402-33.0K,5%,1/16W,CHIP,GA G21497-023               R4U4            

----------------

RES_0402-33.2,1%,1/16W,CHIP,G2A G21796-074               R1B4            
RES_0402-33.2,1%,1/16W,CHIP,G2A G21796-074               R1D1            
RES_0402-33.2,1%,1/16W,CHIP,G2A G21796-074               R1D26           
RES_0402-33.2,1%,1/16W,CHIP,G2A G21796-074               R1D30           
RES_0402-33.2,1%,1/16W,CHIP,G2A G21796-074               R1D33           
RES_0402-33.2,1%,1/16W,CHIP,G2A G21796-074               R1G8            
RES_0402-33.2,1%,1/16W,CHIP,G2A G21796-074               R1L26           
RES_0402-33.2,1%,1/16W,CHIP,G2A G21796-074               R1L29           
RES_0402-33.2,1%,1/16W,CHIP,G2A G21796-074               R1U34           
RES_0402-33.2,1%,1/16W,CHIP,G2A G21796-074               R1U36           
RES_0402-33.2,1%,1/16W,CHIP,G2A G21796-074               R1U40           
RES_0402-33.2,1%,1/16W,CHIP,G2A G21796-074               R1U46           
RES_0402-33.2,1%,1/16W,CHIP,G2A G21796-074               R2M1            
RES_0402-33.2,1%,1/16W,CHIP,G2A G21796-074               R2M3            
RES_0402-33.2,1%,1/16W,CHIP,G2A G21796-074               R2M7            
RES_0402-33.2,1%,1/16W,CHIP,G2A G21796-074               R2N1            
RES_0402-33.2,1%,1/16W,CHIP,G2A G21796-074               R2N26           
RES_0402-33.2,1%,1/16W,CHIP,G2A G21796-074               R2P4            
RES_0402-33.2,1%,1/16W,CHIP,G2A G21796-074               R2R2            
RES_0402-33.2,1%,1/16W,CHIP,G2A G21796-074               R2R10           
RES_0402-33.2,1%,1/16W,CHIP,G2A G21796-074               R2T24           
RES_0402-33.2,1%,1/16W,CHIP,G2A G21796-074               R2T28           
RES_0402-33.2,1%,1/16W,CHIP,G2A G21796-074               R2T30           
RES_0402-33.2,1%,1/16W,CHIP,G2A G21796-074               R2T33           
RES_0402-33.2,1%,1/16W,CHIP,G2A G21796-074               R2T38           
RES_0402-33.2,1%,1/16W,CHIP,G2A G21796-074               R2T47           
RES_0402-33.2,1%,1/16W,CHIP,G2A G21796-074               R3N24           
RES_0402-33.2,1%,1/16W,CHIP,G2A G21796-074               R3N25           
RES_0402-33.2,1%,1/16W,CHIP,G2A G21796-074               R3N26           
RES_0402-33.2,1%,1/16W,CHIP,G2A G21796-074               R3N27           
RES_0402-33.2,1%,1/16W,CHIP,G2A G21796-074               R3N28           
RES_0402-33.2,1%,1/16W,CHIP,G2A G21796-074               R3P42           
RES_0402-33.2,1%,1/16W,CHIP,G2A G21796-074               R3P43           
RES_0402-33.2,1%,1/16W,CHIP,G2A G21796-074               R3P46           
RES_0402-33.2,1%,1/16W,CHIP,G2A G21796-074               R3R3            
RES_0402-33.2,1%,1/16W,CHIP,G2A G21796-074               R3T1            
RES_0402-33.2,1%,1/16W,CHIP,G2A G21796-074               R3T2            
RES_0402-33.2,1%,1/16W,CHIP,G2A G21796-074               R3T10           
RES_0402-33.2,1%,1/16W,CHIP,G2A G21796-074               R3U1            
RES_0402-33.2,1%,1/16W,CHIP,G2A G21796-074               R4A4            
RES_0402-33.2,1%,1/16W,CHIP,G2A G21796-074               R4A6            
RES_0402-33.2,1%,1/16W,CHIP,G2A G21796-074               R4D36           
RES_0402-33.2,1%,1/16W,CHIP,G2A G21796-074               R4D37           
RES_0402-33.2,1%,1/16W,CHIP,G2A G21796-074               R4D65           
RES_0402-33.2,1%,1/16W,CHIP,G2A G21796-074               R4G15           
RES_0402-33.2,1%,1/16W,CHIP,G2A G21796-074               R4G19           
RES_0402-33.2,1%,1/16W,CHIP,G2A G21796-074               R6P45           
RES_0402-33.2,1%,1/16W,CHIP,G2A G21796-074               R7B1            
RES_0402-33.2,1%,1/16W,CHIP,G2A G21796-074               R7C14           
RES_0402-33.2,1%,1/16W,CHIP,G2A G21796-074               R7C16           
RES_0402-33.2,1%,1/16W,CHIP,G2A G21796-074               R7C26           
RES_0402-33.2,1%,1/16W,CHIP,G2A G21796-074               R7D24           
RES_0402-33.2,1%,1/16W,CHIP,G2A G21796-074               R7D25           
RES_0402-33.2,1%,1/16W,CHIP,G2A G21796-074               R7D29           
RES_0402-33.2,1%,1/16W,CHIP,G2A G21796-074               R7D31           
RES_0402-33.2,1%,1/16W,CHIP,G2A G21796-074               R7D34           
RES_0402-33.2,1%,1/16W,CHIP,G2A G21796-074               R7F3            
RES_0402-33.2,1%,1/16W,CHIP,G2A G21796-074               R7F4            
RES_0402-33.2,1%,1/16W,CHIP,G2A G21796-074               R7F23           
RES_0402-33.2,1%,1/16W,CHIP,G2A G21796-074               R7F29           
RES_0402-33.2,1%,1/16W,CHIP,G2A G21796-074               R7F37           
RES_0402-33.2,1%,1/16W,CHIP,G2A G21796-074               R8D11           
RES_0402-33.2,1%,1/16W,CHIP,G2A G21796-074               R8D22           
RES_0402-33.2,1%,1/16W,CHIP,G2A G21796-074               R8D36           
RES_0402-33.2,1%,1/16W,CHIP,G2A G21796-074               R8E5            
RES_0402-33.2,1%,1/16W,CHIP,G2A G21796-074               R8E9            
RES_0402-33.2,1%,1/16W,CHIP,G2A G21796-074               R8E10           
RES_0402-33.2,1%,1/16W,CHIP,G2A G21796-074               R8E13           
RES_0402-33.2,1%,1/16W,CHIP,G2A G21796-074               R8E17           
RES_0402-33.2,1%,1/16W,CHIP,G2A G21796-074               R8E20           
RES_0402-33.2,1%,1/16W,CHIP,G2A G21796-074               R8E24           
RES_0402-33.2,1%,1/16W,CHIP,G2A G21796-074               R8F7            
RES_0402-33.2,1%,1/16W,CHIP,G2A G21796-074               R8F8            
RES_0402-33.2,1%,1/16W,CHIP,G2A G21796-074               R8F12           
RES_0402-33.2,1%,1/16W,CHIP,G2A G21796-074               R8F29           
RES_0402-33.2,1%,1/16W,CHIP,G2A G21796-074               R8G1            
RES_0402-33.2,1%,1/16W,CHIP,G2A G21796-074               R8G24           
RES_0402-33.2,1%,1/16W,CHIP,G2A G21796-074               R8G25           
RES_0402-33.2,1%,1/16W,CHIP,G2A G21796-074               R9A13           
RES_0402-33.2,1%,1/16W,CHIP,G2A G21796-074               R9E5            
RES_0402-33.2,1%,1/16W,CHIP,G2A G21796-074               R9E6            
RES_0402-33.2,1%,1/16W,CHIP,G2A G21796-074               R9E8            
RES_0402-33.2,1%,1/16W,CHIP,G2A G21796-074               R9E9            
RES_0402-33.2,1%,1/16W,CHIP,G2A G21796-074               R9E16           
RES_0402-33.2,1%,1/16W,CHIP,G2A G21796-074               R9F21           
RES_0402-33.2,1%,1/16W,CHIP,G2A G21796-074               R9F34           
RES_0402-33.2,1%,1/16W,CHIP,G2A G21796-074               R9F41           
RES_0402-33.2,1%,1/16W,CHIP,G2A G21796-074               R9G10           
RES_0402-33.2,1%,1/16W,CHIP,G2A G21796-074               R9G16           
RES_0402-33.2,1%,1/16W,CHIP,G2A G21796-074               R9G31           
RES_0402-33.2,1%,1/16W,CHIP,G2A G21796-074               R9P3            

----------------

RES_0402-33.2,1%,1/16W,EMPTY,GA G21796-074               R9A2            

----------------

RES_0402-330,5%,1/16W,CHIP,G21A G21497-028               R1L43           
RES_0402-330,5%,1/16W,CHIP,G21A G21497-028               R1L44           

----------------

RES_0402-348,1%,1/16W,CHIP,G21A G21796-340               R7D15           

----------------

RES_0402-348,1%,1/16W,EMPTY,G2A G21796-340               R9F20           

----------------

RES_0402-4.02K,1%,1/16W,CHIP,GA G21796-082               R1G23           
RES_0402-4.02K,1%,1/16W,CHIP,GA G21796-082               R2L9            
RES_0402-4.02K,1%,1/16W,CHIP,GA G21796-082               R3N22           
RES_0402-4.02K,1%,1/16W,CHIP,GA G21796-082               R6P27           
RES_0402-4.02K,1%,1/16W,CHIP,GA G21796-082               R6P28           
RES_0402-4.02K,1%,1/16W,CHIP,GA G21796-082               R7C24           
RES_0402-4.02K,1%,1/16W,CHIP,GA G21796-082               R7G8            
RES_0402-4.02K,1%,1/16W,CHIP,GA G21796-082               R9N8            

----------------

RES_0402-4.75K,1%,1/16W,CHIP,GA G21796-072               R1B21           
RES_0402-4.75K,1%,1/16W,CHIP,GA G21796-072               R1B24           
RES_0402-4.75K,1%,1/16W,CHIP,GA G21796-072               R1D21           
RES_0402-4.75K,1%,1/16W,CHIP,GA G21796-072               R1D35           
RES_0402-4.75K,1%,1/16W,CHIP,GA G21796-072               R1E12           
RES_0402-4.75K,1%,1/16W,CHIP,GA G21796-072               R1F1            
RES_0402-4.75K,1%,1/16W,CHIP,GA G21796-072               R1L7            
RES_0402-4.75K,1%,1/16W,CHIP,GA G21796-072               R1L27           
RES_0402-4.75K,1%,1/16W,CHIP,GA G21796-072               R1L28           
RES_0402-4.75K,1%,1/16W,CHIP,GA G21796-072               R1R5            
RES_0402-4.75K,1%,1/16W,CHIP,GA G21796-072               R1R11           
RES_0402-4.75K,1%,1/16W,CHIP,GA G21796-072               R1T14           
RES_0402-4.75K,1%,1/16W,CHIP,GA G21796-072               R1U45           
RES_0402-4.75K,1%,1/16W,CHIP,GA G21796-072               R1U48           
RES_0402-4.75K,1%,1/16W,CHIP,GA G21796-072               R2M2            
RES_0402-4.75K,1%,1/16W,CHIP,GA G21796-072               R2M5            
RES_0402-4.75K,1%,1/16W,CHIP,GA G21796-072               R2N7            
RES_0402-4.75K,1%,1/16W,CHIP,GA G21796-072               R2N10           
RES_0402-4.75K,1%,1/16W,CHIP,GA G21796-072               R2N27           
RES_0402-4.75K,1%,1/16W,CHIP,GA G21796-072               R2N32           
RES_0402-4.75K,1%,1/16W,CHIP,GA G21796-072               R2P3            
RES_0402-4.75K,1%,1/16W,CHIP,GA G21796-072               R2P5            
RES_0402-4.75K,1%,1/16W,CHIP,GA G21796-072               R2P13           
RES_0402-4.75K,1%,1/16W,CHIP,GA G21796-072               R2P17           
RES_0402-4.75K,1%,1/16W,CHIP,GA G21796-072               R2R7            
RES_0402-4.75K,1%,1/16W,CHIP,GA G21796-072               R2T3            
RES_0402-4.75K,1%,1/16W,CHIP,GA G21796-072               R2T6            
RES_0402-4.75K,1%,1/16W,CHIP,GA G21796-072               R2T11           
RES_0402-4.75K,1%,1/16W,CHIP,GA G21796-072               R2T34           
RES_0402-4.75K,1%,1/16W,CHIP,GA G21796-072               R2T35           
RES_0402-4.75K,1%,1/16W,CHIP,GA G21796-072               R2U2            
RES_0402-4.75K,1%,1/16W,CHIP,GA G21796-072               R2U4            
RES_0402-4.75K,1%,1/16W,CHIP,GA G21796-072               R2U30           
RES_0402-4.75K,1%,1/16W,CHIP,GA G21796-072               R2U48           
RES_0402-4.75K,1%,1/16W,CHIP,GA G21796-072               R3N11           
RES_0402-4.75K,1%,1/16W,CHIP,GA G21796-072               R3N12           
RES_0402-4.75K,1%,1/16W,CHIP,GA G21796-072               R3N13           
RES_0402-4.75K,1%,1/16W,CHIP,GA G21796-072               R3P44           
RES_0402-4.75K,1%,1/16W,CHIP,GA G21796-072               R3P53           
RES_0402-4.75K,1%,1/16W,CHIP,GA G21796-072               R3R4            
RES_0402-4.75K,1%,1/16W,CHIP,GA G21796-072               R3R10           
RES_0402-4.75K,1%,1/16W,CHIP,GA G21796-072               R3R16           
RES_0402-4.75K,1%,1/16W,CHIP,GA G21796-072               R3T5            
RES_0402-4.75K,1%,1/16W,CHIP,GA G21796-072               R4D40           
RES_0402-4.75K,1%,1/16W,CHIP,GA G21796-072               R4D41           
RES_0402-4.75K,1%,1/16W,CHIP,GA G21796-072               R4D69           
RES_0402-4.75K,1%,1/16W,CHIP,GA G21796-072               R4D70           
RES_0402-4.75K,1%,1/16W,CHIP,GA G21796-072               R4R5            
RES_0402-4.75K,1%,1/16W,CHIP,GA G21796-072               R4U1            
RES_0402-4.75K,1%,1/16W,CHIP,GA G21796-072               R4U3            
RES_0402-4.75K,1%,1/16W,CHIP,GA G21796-072               R6M4            
RES_0402-4.75K,1%,1/16W,CHIP,GA G21796-072               R6M9            
RES_0402-4.75K,1%,1/16W,CHIP,GA G21796-072               R6P39           
RES_0402-4.75K,1%,1/16W,CHIP,GA G21796-072               R6P48           
RES_0402-4.75K,1%,1/16W,CHIP,GA G21796-072               R7C17           
RES_0402-4.75K,1%,1/16W,CHIP,GA G21796-072               R7D3            
RES_0402-4.75K,1%,1/16W,CHIP,GA G21796-072               R7D6            
RES_0402-4.75K,1%,1/16W,CHIP,GA G21796-072               R7D30           
RES_0402-4.75K,1%,1/16W,CHIP,GA G21796-072               R7D42           
RES_0402-4.75K,1%,1/16W,CHIP,GA G21796-072               R7D44           
RES_0402-4.75K,1%,1/16W,CHIP,GA G21796-072               R7E7            
RES_0402-4.75K,1%,1/16W,CHIP,GA G21796-072               R7E10           
RES_0402-4.75K,1%,1/16W,CHIP,GA G21796-072               R7E11           
RES_0402-4.75K,1%,1/16W,CHIP,GA G21796-072               R7E18           
RES_0402-4.75K,1%,1/16W,CHIP,GA G21796-072               R7E21           
RES_0402-4.75K,1%,1/16W,CHIP,GA G21796-072               R7F5            
RES_0402-4.75K,1%,1/16W,CHIP,GA G21796-072               R7F33           
RES_0402-4.75K,1%,1/16W,CHIP,GA G21796-072               R7G7            
RES_0402-4.75K,1%,1/16W,CHIP,GA G21796-072               R8B3            
RES_0402-4.75K,1%,1/16W,CHIP,GA G21796-072               R8B5            
RES_0402-4.75K,1%,1/16W,CHIP,GA G21796-072               R8B8            
RES_0402-4.75K,1%,1/16W,CHIP,GA G21796-072               R8B10           
RES_0402-4.75K,1%,1/16W,CHIP,GA G21796-072               R8B16           
RES_0402-4.75K,1%,1/16W,CHIP,GA G21796-072               R8B17           
RES_0402-4.75K,1%,1/16W,CHIP,GA G21796-072               R8B18           
RES_0402-4.75K,1%,1/16W,CHIP,GA G21796-072               R8B19           
RES_0402-4.75K,1%,1/16W,CHIP,GA G21796-072               R8B25           
RES_0402-4.75K,1%,1/16W,CHIP,GA G21796-072               R8B31           
RES_0402-4.75K,1%,1/16W,CHIP,GA G21796-072               R8C1            
RES_0402-4.75K,1%,1/16W,CHIP,GA G21796-072               R8C2            
RES_0402-4.75K,1%,1/16W,CHIP,GA G21796-072               R8C6            
RES_0402-4.75K,1%,1/16W,CHIP,GA G21796-072               R8C7            
RES_0402-4.75K,1%,1/16W,CHIP,GA G21796-072               R8C9            
RES_0402-4.75K,1%,1/16W,CHIP,GA G21796-072               R8C25           
RES_0402-4.75K,1%,1/16W,CHIP,GA G21796-072               R8D14           
RES_0402-4.75K,1%,1/16W,CHIP,GA G21796-072               R8D25           
RES_0402-4.75K,1%,1/16W,CHIP,GA G21796-072               R8D26           
RES_0402-4.75K,1%,1/16W,CHIP,GA G21796-072               R8D29           
RES_0402-4.75K,1%,1/16W,CHIP,GA G21796-072               R8D31           
RES_0402-4.75K,1%,1/16W,CHIP,GA G21796-072               R8D37           
RES_0402-4.75K,1%,1/16W,CHIP,GA G21796-072               R8E14           
RES_0402-4.75K,1%,1/16W,CHIP,GA G21796-072               R8E22           
RES_0402-4.75K,1%,1/16W,CHIP,GA G21796-072               R8E23           
RES_0402-4.75K,1%,1/16W,CHIP,GA G21796-072               R8E32           
RES_0402-4.75K,1%,1/16W,CHIP,GA G21796-072               R8F13           
RES_0402-4.75K,1%,1/16W,CHIP,GA G21796-072               R8F14           
RES_0402-4.75K,1%,1/16W,CHIP,GA G21796-072               R8F24           
RES_0402-4.75K,1%,1/16W,CHIP,GA G21796-072               R8F34           
RES_0402-4.75K,1%,1/16W,CHIP,GA G21796-072               R8G2            
RES_0402-4.75K,1%,1/16W,CHIP,GA G21796-072               R8G23           
RES_0402-4.75K,1%,1/16W,CHIP,GA G21796-072               R9A18           
RES_0402-4.75K,1%,1/16W,CHIP,GA G21796-072               R9A21           
RES_0402-4.75K,1%,1/16W,CHIP,GA G21796-072               R9E21           
RES_0402-4.75K,1%,1/16W,CHIP,GA G21796-072               R9F3            
RES_0402-4.75K,1%,1/16W,CHIP,GA G21796-072               R9F9            
RES_0402-4.75K,1%,1/16W,CHIP,GA G21796-072               R9F14           
RES_0402-4.75K,1%,1/16W,CHIP,GA G21796-072               R9F15           
RES_0402-4.75K,1%,1/16W,CHIP,GA G21796-072               R9F16           
RES_0402-4.75K,1%,1/16W,CHIP,GA G21796-072               R9F29           
RES_0402-4.75K,1%,1/16W,CHIP,GA G21796-072               R9F30           
RES_0402-4.75K,1%,1/16W,CHIP,GA G21796-072               R9F35           
RES_0402-4.75K,1%,1/16W,CHIP,GA G21796-072               R9F40           
RES_0402-4.75K,1%,1/16W,CHIP,GA G21796-072               R9F47           
RES_0402-4.75K,1%,1/16W,CHIP,GA G21796-072               R9F52           
RES_0402-4.75K,1%,1/16W,CHIP,GA G21796-072               R9F55           
RES_0402-4.75K,1%,1/16W,CHIP,GA G21796-072               R9G21           
RES_0402-4.75K,1%,1/16W,CHIP,GA G21796-072               R9T5            
RES_0402-4.75K,1%,1/16W,CHIP,GA G21796-072               R9T9            

----------------

RES_0402-4.75K,1%,1/16W,EMPTY,A G21796-072               R1D27           
RES_0402-4.75K,1%,1/16W,EMPTY,A G21796-072               R1D29           
RES_0402-4.75K,1%,1/16W,EMPTY,A G21796-072               R1L19           
RES_0402-4.75K,1%,1/16W,EMPTY,A G21796-072               R1T13           
RES_0402-4.75K,1%,1/16W,EMPTY,A G21796-072               R1T16           
RES_0402-4.75K,1%,1/16W,EMPTY,A G21796-072               R1T17           
RES_0402-4.75K,1%,1/16W,EMPTY,A G21796-072               R1T18           
RES_0402-4.75K,1%,1/16W,EMPTY,A G21796-072               R1T19           
RES_0402-4.75K,1%,1/16W,EMPTY,A G21796-072               R1T20           
RES_0402-4.75K,1%,1/16W,EMPTY,A G21796-072               R1T21           
RES_0402-4.75K,1%,1/16W,EMPTY,A G21796-072               R1T22           
RES_0402-4.75K,1%,1/16W,EMPTY,A G21796-072               R3N2            
RES_0402-4.75K,1%,1/16W,EMPTY,A G21796-072               R3P62           
RES_0402-4.75K,1%,1/16W,EMPTY,A G21796-072               R3T3            
RES_0402-4.75K,1%,1/16W,EMPTY,A G21796-072               R6P22           
RES_0402-4.75K,1%,1/16W,EMPTY,A G21796-072               R6P23           
RES_0402-4.75K,1%,1/16W,EMPTY,A G21796-072               R7C22           
RES_0402-4.75K,1%,1/16W,EMPTY,A G21796-072               R7F6            
RES_0402-4.75K,1%,1/16W,EMPTY,A G21796-072               R8E12           
RES_0402-4.75K,1%,1/16W,EMPTY,A G21796-072               R8E19           
RES_0402-4.75K,1%,1/16W,EMPTY,A G21796-072               R8F16           
RES_0402-4.75K,1%,1/16W,EMPTY,A G21796-072               R9F10           
RES_0402-4.75K,1%,1/16W,EMPTY,A G21796-072               R9F17           
RES_0402-4.75K,1%,1/16W,EMPTY,A G21796-072               R9F18           
RES_0402-4.75K,1%,1/16W,EMPTY,A G21796-072               R9F19           
RES_0402-4.75K,1%,1/16W,EMPTY,A G21796-072               R9F36           
RES_0402-4.75K,1%,1/16W,EMPTY,A G21796-072               R9F37           
RES_0402-4.75K,1%,1/16W,EMPTY,A G21796-072               R9F38           
RES_0402-4.75K,1%,1/16W,EMPTY,A G21796-072               R9F39           
RES_0402-4.75K,1%,1/16W,EMPTY,A G21796-072               R9F48           
RES_0402-4.75K,1%,1/16W,EMPTY,A G21796-072               R9F49           
RES_0402-4.75K,1%,1/16W,EMPTY,A G21796-072               R9G23           
RES_0402-4.75K,1%,1/16W,EMPTY,A G21796-072               R9G25           

----------------

RES_0402-4.99K,1%,1/16W,CHIP,GA G21796-013               R9E23           
RES_0402-4.99K,1%,1/16W,CHIP,GA G21796-013               R9P12           

----------------

RES_0402-40.2K,1%,1/16W,CHIP,GA G21796-133               R1D40           
RES_0402-40.2K,1%,1/16W,CHIP,GA G21796-133               R1L4            

----------------

RES_0402-42.2,1.0%,1/16W,EMPTYA G21796-259               R4D18           
RES_0402-42.2,1.0%,1/16W,EMPTYA G21796-259               R4D24           
RES_0402-42.2,1.0%,1/16W,EMPTYA G21796-259               R6P1            
RES_0402-42.2,1.0%,1/16W,EMPTYA G21796-259               R6P2            
RES_0402-42.2,1.0%,1/16W,EMPTYA G21796-259               R6P3            
RES_0402-42.2,1.0%,1/16W,EMPTYA G21796-259               R6P4            
RES_0402-42.2,1.0%,1/16W,EMPTYA G21796-259               R6P5            
RES_0402-42.2,1.0%,1/16W,EMPTYA G21796-259               R6P6            
RES_0402-42.2,1.0%,1/16W,EMPTYA G21796-259               R6P7            
RES_0402-42.2,1.0%,1/16W,EMPTYA G21796-259               R6P8            
RES_0402-42.2,1.0%,1/16W,EMPTYA G21796-259               R6P9            
RES_0402-42.2,1.0%,1/16W,EMPTYA G21796-259               R6P11           
RES_0402-42.2,1.0%,1/16W,EMPTYA G21796-259               R6P12           
RES_0402-42.2,1.0%,1/16W,EMPTYA G21796-259               R6P13           
RES_0402-42.2,1.0%,1/16W,EMPTYA G21796-259               R6P15           
RES_0402-42.2,1.0%,1/16W,EMPTYA G21796-259               R6P17           
RES_0402-42.2,1.0%,1/16W,EMPTYA G21796-259               R7P1            
RES_0402-42.2,1.0%,1/16W,EMPTYA G21796-259               R7P2            
RES_0402-42.2,1.0%,1/16W,EMPTYA G21796-259               R7P3            
RES_0402-42.2,1.0%,1/16W,EMPTYA G21796-259               R7P4            
RES_0402-42.2,1.0%,1/16W,EMPTYA G21796-259               R7P6            
RES_0402-42.2,1.0%,1/16W,EMPTYA G21796-259               R7P7            
RES_0402-42.2,1.0%,1/16W,EMPTYA G21796-259               R7P9            
RES_0402-42.2,1.0%,1/16W,EMPTYA G21796-259               R7P12           

----------------

RES_0402-470.0,5%,1/16W,CHIP,GA G21497-024               R1L8            

----------------

RES_0402-475.0,1%,1/16W,CHIP,GA G21796-077               R8F25           
RES_0402-475.0,1%,1/16W,CHIP,GA G21796-077               R9A4            

----------------

RES_0402-49.9,1%,1/16W,CHIP,G2A G21796-047               R1L16           
RES_0402-49.9,1%,1/16W,CHIP,G2A G21796-047               R1M22           
RES_0402-49.9,1%,1/16W,CHIP,G2A G21796-047               R1U43           
RES_0402-49.9,1%,1/16W,CHIP,G2A G21796-047               R2N19           
RES_0402-49.9,1%,1/16W,CHIP,G2A G21796-047               R2N22           
RES_0402-49.9,1%,1/16W,CHIP,G2A G21796-047               R2N31           
RES_0402-49.9,1%,1/16W,CHIP,G2A G21796-047               R2T18           
RES_0402-49.9,1%,1/16W,CHIP,G2A G21796-047               R2T36           
RES_0402-49.9,1%,1/16W,CHIP,G2A G21796-047               R3B2            
RES_0402-49.9,1%,1/16W,CHIP,G2A G21796-047               R3D4            
RES_0402-49.9,1%,1/16W,CHIP,G2A G21796-047               R3D9            
RES_0402-49.9,1%,1/16W,CHIP,G2A G21796-047               R3D15           
RES_0402-49.9,1%,1/16W,CHIP,G2A G21796-047               R3D19           
RES_0402-49.9,1%,1/16W,CHIP,G2A G21796-047               R3D20           
RES_0402-49.9,1%,1/16W,CHIP,G2A G21796-047               R3L13           
RES_0402-49.9,1%,1/16W,CHIP,G2A G21796-047               R3P45           
RES_0402-49.9,1%,1/16W,CHIP,G2A G21796-047               R4E9            
RES_0402-49.9,1%,1/16W,CHIP,G2A G21796-047               R4P2            
RES_0402-49.9,1%,1/16W,CHIP,G2A G21796-047               R4P3            
RES_0402-49.9,1%,1/16W,CHIP,G2A G21796-047               R4P4            
RES_0402-49.9,1%,1/16W,CHIP,G2A G21796-047               R4P18           
RES_0402-49.9,1%,1/16W,CHIP,G2A G21796-047               R4P19           
RES_0402-49.9,1%,1/16W,CHIP,G2A G21796-047               R4R6            
RES_0402-49.9,1%,1/16W,CHIP,G2A G21796-047               R5P2            
RES_0402-49.9,1%,1/16W,CHIP,G2A G21796-047               R5P3            
RES_0402-49.9,1%,1/16W,CHIP,G2A G21796-047               R5P4            
RES_0402-49.9,1%,1/16W,CHIP,G2A G21796-047               R5R1            
RES_0402-49.9,1%,1/16W,CHIP,G2A G21796-047               R6B1            
RES_0402-49.9,1%,1/16W,CHIP,G2A G21796-047               R6D2            
RES_0402-49.9,1%,1/16W,CHIP,G2A G21796-047               R6D5            
RES_0402-49.9,1%,1/16W,CHIP,G2A G21796-047               R6D8            
RES_0402-49.9,1%,1/16W,CHIP,G2A G21796-047               R6D11           
RES_0402-49.9,1%,1/16W,CHIP,G2A G21796-047               R6D12           
RES_0402-49.9,1%,1/16W,CHIP,G2A G21796-047               R6F1            
RES_0402-49.9,1%,1/16W,CHIP,G2A G21796-047               R6F2            
RES_0402-49.9,1%,1/16W,CHIP,G2A G21796-047               R6F4            
RES_0402-49.9,1%,1/16W,CHIP,G2A G21796-047               R6F5            
RES_0402-49.9,1%,1/16W,CHIP,G2A G21796-047               R6M8            
RES_0402-49.9,1%,1/16W,CHIP,G2A G21796-047               R6N1            
RES_0402-49.9,1%,1/16W,CHIP,G2A G21796-047               R7D33           
RES_0402-49.9,1%,1/16W,CHIP,G2A G21796-047               R7P8            
RES_0402-49.9,1%,1/16W,CHIP,G2A G21796-047               R7P10           
RES_0402-49.9,1%,1/16W,CHIP,G2A G21796-047               R7P11           
RES_0402-49.9,1%,1/16W,CHIP,G2A G21796-047               R7P25           
RES_0402-49.9,1%,1/16W,CHIP,G2A G21796-047               R7P26           
RES_0402-49.9,1%,1/16W,CHIP,G2A G21796-047               R8B29           
RES_0402-49.9,1%,1/16W,CHIP,G2A G21796-047               R8D19           
RES_0402-49.9,1%,1/16W,CHIP,G2A G21796-047               R8D20           
RES_0402-49.9,1%,1/16W,CHIP,G2A G21796-047               R8P1            
RES_0402-49.9,1%,1/16W,CHIP,G2A G21796-047               R8P2            
RES_0402-49.9,1%,1/16W,CHIP,G2A G21796-047               R8P3            
RES_0402-49.9,1%,1/16W,CHIP,G2A G21796-047               R8R1            
RES_0402-49.9,1%,1/16W,CHIP,G2A G21796-047               R9B4            
RES_0402-49.9,1%,1/16W,CHIP,G2A G21796-047               R9B5            
RES_0402-49.9,1%,1/16W,CHIP,G2A G21796-047               R9B10           
RES_0402-49.9,1%,1/16W,CHIP,G2A G21796-047               R9M6            
RES_0402-49.9,1%,1/16W,CHIP,G2A G21796-047               R9N1            
RES_0402-49.9,1%,1/16W,CHIP,G2A G21796-047               R9P2            
RES_0402-49.9,1%,1/16W,CHIP,G2A G21796-047               R9R5            
RES_0402-49.9,1%,1/16W,CHIP,G2A G21796-047               R9R6            

----------------

RES_0402-49.9,1%,1/16W,EMPTY,GA G21796-047               R3N14           
RES_0402-49.9,1%,1/16W,EMPTY,GA G21796-047               R3P17           
RES_0402-49.9,1%,1/16W,EMPTY,GA G21796-047               R3T11           
RES_0402-49.9,1%,1/16W,EMPTY,GA G21796-047               R8B21           
RES_0402-49.9,1%,1/16W,EMPTY,GA G21796-047               R9U4            

----------------

RES_0402-49.9K,1%,1/16W,CHIP,GA G21796-048               R2L19           
RES_0402-49.9K,1%,1/16W,CHIP,GA G21796-048               R8D39           
RES_0402-49.9K,1%,1/16W,CHIP,GA G21796-048               R9G7            

----------------

RES_0402-5.11K,1%,1/16W,CHIP,GA G21796-140               R1U26           
RES_0402-5.11K,1%,1/16W,CHIP,GA G21796-140               R1U29           
RES_0402-5.11K,1%,1/16W,CHIP,GA G21796-140               R1U32           
RES_0402-5.11K,1%,1/16W,CHIP,GA G21796-140               R1U39           
RES_0402-5.11K,1%,1/16W,CHIP,GA G21796-140               R1U47           
RES_0402-5.11K,1%,1/16W,CHIP,GA G21796-140               R8A10           

----------------

RES_0402-5.36K,1.0%,1/16W,CHIPA G21796-297               R1B15           
RES_0402-5.36K,1.0%,1/16W,CHIPA G21796-297               R1G22           

----------------

RES_0402-5.76K,1%,1/16W,CHIP,GA G21796-143               R9F6            

----------------

RES_0402-51,5.0%,1/16W,CHIP,G2A G21497-048               R1U12           
RES_0402-51,5.0%,1/16W,CHIP,G2A G21497-048               R1U13           
RES_0402-51,5.0%,1/16W,CHIP,G2A G21497-048               R1U14           
RES_0402-51,5.0%,1/16W,CHIP,G2A G21497-048               R2R6            

----------------

RES_0402-51.1,1.0%,1/16W,CHIP,A G21796-208               R2N25           
RES_0402-51.1,1.0%,1/16W,CHIP,A G21796-208               R4A1            
RES_0402-51.1,1.0%,1/16W,CHIP,A G21796-208               R6L7            
RES_0402-51.1,1.0%,1/16W,CHIP,A G21796-208               R6N4            
RES_0402-51.1,1.0%,1/16W,CHIP,A G21796-208               R6U8            
RES_0402-51.1,1.0%,1/16W,CHIP,A G21796-208               R6U16           
RES_0402-51.1,1.0%,1/16W,CHIP,A G21796-208               R7C3            
RES_0402-51.1,1.0%,1/16W,CHIP,A G21796-208               R7P29           
RES_0402-51.1,1.0%,1/16W,CHIP,A G21796-208               R7R1            
RES_0402-51.1,1.0%,1/16W,CHIP,A G21796-208               R8B1            
RES_0402-51.1,1.0%,1/16W,CHIP,A G21796-208               R9N4            

----------------

RES_0402-560,5%,1/16W,CHIP,G21A G21497-062               R2P8            

----------------

RES_0402-6.19K,1%,1/16W,CHIP,GA G21796-161               R1D31           
RES_0402-6.19K,1%,1/16W,CHIP,GA G21796-161               R9T3            

----------------

RES_0402-6.34K,1%,1/16W,CHIP,GA G21796-146               R3P51           
RES_0402-6.34K,1%,1/16W,CHIP,GA G21796-146               R4B4            
RES_0402-6.34K,1%,1/16W,CHIP,GA G21796-146               R4G9            
RES_0402-6.34K,1%,1/16W,CHIP,GA G21796-146               R7B13           
RES_0402-6.34K,1%,1/16W,CHIP,GA G21796-146               R7F11           

----------------

RES_0402-63.4K,1.0%,1/16W,CHIPA G21796-327               R2L20           

----------------

RES_0402-64.9,1.0%,1/16W,CHIP,A G21796-298               R1L21           
RES_0402-64.9,1.0%,1/16W,CHIP,A G21796-298               R3D21           
RES_0402-64.9,1.0%,1/16W,CHIP,A G21796-298               R3P29           
RES_0402-64.9,1.0%,1/16W,CHIP,A G21796-298               R3P38           
RES_0402-64.9,1.0%,1/16W,CHIP,A G21796-298               R7M9            

----------------

RES_0402-64.9K,1%,1/16W,CHIP,GA G21796-148               R8F9            

----------------

RES_0402-665,1.0%,1/16W,CHIP,GA G21796-235               R1T2            
RES_0402-665,1.0%,1/16W,CHIP,GA G21796-235               R1T3            
RES_0402-665,1.0%,1/16W,CHIP,GA G21796-235               R2N5            
RES_0402-665,1.0%,1/16W,CHIP,GA G21796-235               R2N8            
RES_0402-665,1.0%,1/16W,CHIP,GA G21796-235               R2T53           
RES_0402-665,1.0%,1/16W,CHIP,GA G21796-235               R2T54           
RES_0402-665,1.0%,1/16W,CHIP,GA G21796-235               R2U3            
RES_0402-665,1.0%,1/16W,CHIP,GA G21796-235               R2U11           
RES_0402-665,1.0%,1/16W,CHIP,GA G21796-235               R2U38           
RES_0402-665,1.0%,1/16W,CHIP,GA G21796-235               R2U39           
RES_0402-665,1.0%,1/16W,CHIP,GA G21796-235               R3R5            
RES_0402-665,1.0%,1/16W,CHIP,GA G21796-235               R3R12           
RES_0402-665,1.0%,1/16W,CHIP,GA G21796-235               R4T7            
RES_0402-665,1.0%,1/16W,CHIP,GA G21796-235               R4T8            
RES_0402-665,1.0%,1/16W,CHIP,GA G21796-235               R6U17           
RES_0402-665,1.0%,1/16W,CHIP,GA G21796-235               R6U18           
RES_0402-665,1.0%,1/16W,CHIP,GA G21796-235               R7M1            
RES_0402-665,1.0%,1/16W,CHIP,GA G21796-235               R7M6            

----------------

RES_0402-68.1K,1%,1/16W,EMPTY,A G21796-187               R1A2            
RES_0402-68.1K,1%,1/16W,EMPTY,A G21796-187               R1A3            
RES_0402-68.1K,1%,1/16W,EMPTY,A G21796-187               R1C37           
RES_0402-68.1K,1%,1/16W,EMPTY,A G21796-187               R1D52           
RES_0402-68.1K,1%,1/16W,EMPTY,A G21796-187               R1D54           
RES_0402-68.1K,1%,1/16W,EMPTY,A G21796-187               R1D55           
RES_0402-68.1K,1%,1/16W,EMPTY,A G21796-187               R1E13           
RES_0402-68.1K,1%,1/16W,EMPTY,A G21796-187               R1E14           
RES_0402-68.1K,1%,1/16W,EMPTY,A G21796-187               R1G25           
RES_0402-68.1K,1%,1/16W,EMPTY,A G21796-187               R1G26           
RES_0402-68.1K,1%,1/16W,EMPTY,A G21796-187               R3L14           
RES_0402-68.1K,1%,1/16W,EMPTY,A G21796-187               R3L15           
RES_0402-68.1K,1%,1/16W,EMPTY,A G21796-187               R4C13           
RES_0402-68.1K,1%,1/16W,EMPTY,A G21796-187               R4D68           
RES_0402-68.1K,1%,1/16W,EMPTY,A G21796-187               R4D71           
RES_0402-68.1K,1%,1/16W,EMPTY,A G21796-187               R4D72           
RES_0402-68.1K,1%,1/16W,EMPTY,A G21796-187               R4E19           
RES_0402-68.1K,1%,1/16W,EMPTY,A G21796-187               R4E21           
RES_0402-68.1K,1%,1/16W,EMPTY,A G21796-187               R4E22           
RES_0402-68.1K,1%,1/16W,EMPTY,A G21796-187               R7A20           
RES_0402-68.1K,1%,1/16W,EMPTY,A G21796-187               R7A21           
RES_0402-68.1K,1%,1/16W,EMPTY,A G21796-187               R7C25           
RES_0402-68.1K,1%,1/16W,EMPTY,A G21796-187               R7G25           
RES_0402-68.1K,1%,1/16W,EMPTY,A G21796-187               R7G30           

----------------

RES_0402-69.8K,1%,1/16W,CHIP,GA G21796-007               R1D16           

----------------

RES_0402-7.5K,1%,1/16W,CHIP,G2A G21796-177               R1D43           

----------------

RES_0402-7.87K,1.0%,1/16W,CHIPA G21796-242               R4B6            
RES_0402-7.87K,1.0%,1/16W,CHIPA G21796-242               R4B8            
RES_0402-7.87K,1.0%,1/16W,CHIPA G21796-242               R4G11           
RES_0402-7.87K,1.0%,1/16W,CHIPA G21796-242               R4G13           
RES_0402-7.87K,1.0%,1/16W,CHIPA G21796-242               R7B14           
RES_0402-7.87K,1.0%,1/16W,CHIPA G21796-242               R7B16           
RES_0402-7.87K,1.0%,1/16W,CHIPA G21796-242               R7F15           
RES_0402-7.87K,1.0%,1/16W,CHIPA G21796-242               R7F18           

----------------

RES_0402-75,1.0%,1/16W,CHIP,G2A G21796-267               R2T9            
RES_0402-75,1.0%,1/16W,CHIP,G2A G21796-267               R2T16           
RES_0402-75,1.0%,1/16W,CHIP,G2A G21796-267               R2T31           
RES_0402-75,1.0%,1/16W,CHIP,G2A G21796-267               R2T43           
RES_0402-75,1.0%,1/16W,CHIP,G2A G21796-267               R3P41           
RES_0402-75,1.0%,1/16W,CHIP,G2A G21796-267               R7E2            

----------------

RES_0402-75K,1%,1/16W,CHIP,G21A G21796-224               R7E14           

----------------

RES_0402-8.06K,1%,1/16W,CHIP,GA G21796-078               R4C12           
RES_0402-8.06K,1%,1/16W,CHIP,GA G21796-078               R7A8            
RES_0402-8.06K,1%,1/16W,CHIP,GA G21796-078               R7G10           

----------------

RES_0402-8.2K,1%,1/16W,CHIP,G2A G21796-345               R1T25           
RES_0402-8.2K,1%,1/16W,CHIP,G2A G21796-345               R1U27           
RES_0402-8.2K,1%,1/16W,CHIP,G2A G21796-345               R1U38           

----------------

RES_0402-8.2K,1%,1/16W,EMPTY,GA G21796-345               R7D13           

----------------

RES_0402-90.9,1%,1/16W,CHIP,G2A G21796-365               R3D1            
RES_0402-90.9,1%,1/16W,CHIP,G2A G21796-365               R3D2            
RES_0402-90.9,1%,1/16W,CHIP,G2A G21796-365               R4P8            
RES_0402-90.9,1%,1/16W,CHIP,G2A G21796-365               R4P10           
RES_0402-90.9,1%,1/16W,CHIP,G2A G21796-365               R5D1            
RES_0402-90.9,1%,1/16W,CHIP,G2A G21796-365               R5D2            
RES_0402-90.9,1%,1/16W,CHIP,G2A G21796-365               R7P16           
RES_0402-90.9,1%,1/16W,CHIP,G2A G21796-365               R7P17           

----------------

RES_0402-90.9K,1%,1/16W,CHIP,GA G21796-058               R1D13           
RES_0402-90.9K,1%,1/16W,CHIP,GA G21796-058               R3P48           

----------------

RES_0603-0,5.0%,1/10W,CHIP,G22A G22178-002               R1R15           
RES_0603-0,5.0%,1/10W,CHIP,G22A G22178-002               R1T32           
RES_0603-0,5.0%,1/10W,CHIP,G22A G22178-002               R1T34           

----------------

RES_0603-0,5.0%,1/10W,EMPTY,G2A G22178-002               R1T33           

----------------

RES_0603-10.0,1%,1/10W,CHIP,G2A G22026-041               R2L8            
RES_0603-10.0,1%,1/10W,CHIP,G2A G22026-041               R9P30           

----------------

RES_0603-100.0,1%,1/10W,CHIP,GA G22026-038               R1E3            
RES_0603-100.0,1%,1/10W,CHIP,GA G22026-038               R4E13           

----------------

RES_0603-100.0K,1%,1/10W,CHIP,A G22026-050               R5P1            
RES_0603-100.0K,1%,1/10W,CHIP,A G22026-050               RT8P1           

----------------

RES_0603-10M,1.0%,1/10W,CHIP,GA G22026-112               R7C6            

----------------

RES_0603-120.0,1%,1/10W,CHIP,GA G22026-003               R1A1            
RES_0603-120.0,1%,1/10W,CHIP,GA G22026-003               R1G20           
RES_0603-120.0,1%,1/10W,CHIP,GA G22026-003               R3U4            
RES_0603-120.0,1%,1/10W,CHIP,GA G22026-003               R4B2            
RES_0603-120.0,1%,1/10W,CHIP,GA G22026-003               R4G6            
RES_0603-120.0,1%,1/10W,CHIP,GA G22026-003               R4L4            
RES_0603-120.0,1%,1/10W,CHIP,GA G22026-003               R7B10           
RES_0603-120.0,1%,1/10W,CHIP,GA G22026-003               R7F10           

----------------

RES_0603-2.2,1.0%,1/10W,CHIP,GA G22026-127               R2T21           
RES_0603-2.2,1.0%,1/10W,CHIP,GA G22026-127               R2T23           
RES_0603-2.2,1.0%,1/10W,CHIP,GA G22026-127               R2T52           
RES_0603-2.2,1.0%,1/10W,CHIP,GA G22026-127               R3D14           
RES_0603-2.2,1.0%,1/10W,CHIP,GA G22026-127               R6P25           

----------------

RES_0603-200K,0.1%,1/10W,CHIP,A G22369-010               R7C1            

----------------

RES_0603-475.0,1%,1/10W,CHIP,GA G22026-030               R8A12           

----------------

RES_0805-0.0,5%,1/8W,CHIP,G221A G22179-004               R1D41           

----------------

RES_1206-0.002,1%,1W,CHIP,G521A G52199-004               R1F3            
RES_1206-0.002,1%,1W,CHIP,G521A G52199-004               R4B12           
RES_1206-0.002,1%,1W,CHIP,G521A G52199-004               R4F2            
RES_1206-0.002,1%,1W,CHIP,G521A G52199-004               R9M4            

----------------

RES_2010-0.001,1%,1W,CHIP,E309A E30969-002               R1B20           
RES_2010-0.001,1%,1W,CHIP,E309A E30969-002               R4C6            

----------------

RES_PWR_6PAD-0.001,1%,3W,CHIP,A E74391-005               R1D49           
RES_PWR_6PAD-0.001,1%,3W,CHIP,A E74391-005               R9R1            

----------------

RT8240_QFN-IC,H66262-001 H66262-001               EU8F1           

----------------

RT9059_DFN-IC,H65765-001 H65765-001               EU8A2           
RT9059_DFN-IC,H65765-001 H65765-001               EU9F1           
RT9059_DFN-IC,H65765-001 H65765-001               EU9F2           

----------------

SC2K2P50V3KX-GP_SMD-BCG6-SC2K2A                          CTI3            
SC2K2P50V3KX-GP_SMD-BCG6-SC2K2A                          CTI5            
SC2K2P50V3KX-GP_SMD-BCG6-SC2K2A                          CTI9            
SC2K2P50V3KX-GP_SMD-BCG6-SC2K2A                          CTI11           
SC2K2P50V3KX-GP_SMD-BCG6-SC2K2A                          CTI14           
SC2K2P50V3KX-GP_SMD-BCG6-SC2K2A                          CTI18           
SC2K2P50V3KX-GP_SMD-BCG6-SC2K2A                          CTI20           
SC2K2P50V3KX-GP_SMD-BCG6-SC2K2A                          CTI23           
SC2K2P50V3KX-GP_SMD-BCG6-SC2K2A                          CTI27           
SC2K2P50V3KX-GP_SMD-BCG6-SC2K2A                          CTI29           
SC2K2P50V3KX-GP_SMD-BCG6-SC2K2A                          CTI33           
SC2K2P50V3KX-GP_SMD-BCG6-SC2K2A                          CTI35           
SC2K2P50V3KX-GP_SMD-BCG6-SC2K2A                          CTI38           
SC2K2P50V3KX-GP_SMD-BCG6-SC2K2A                          CTI41           
SC2K2P50V3KX-GP_SMD-BCG6-SC2K2A                          CTI44           
SC2K2P50V3KX-GP_SMD-BCG6-SC2K2A                          CTI47           
SC2K2P50V3KX-GP_SMD-BCG6-SC2K2A                          CTI50           
SC2K2P50V3KX-GP_SMD-BCG6-SC2K2A                          CTI53           
SC2K2P50V3KX-GP_SMD-BCG6-SC2K2A                          CTI56           
SC2K2P50V3KX-GP_SMD-BCG6-SC2K2A                          CTI59           
SC2K2P50V3KX-GP_SMD-BCG6-SC2K2A                          CTI62           
SC2K2P50V3KX-GP_SMD-BCG6-SC2K2A                          CTI65           
SC2K2P50V3KX-GP_SMD-BCG6-SC2K2A                          CTI68           
SC2K2P50V3KX-GP_SMD-BCG6-SC2K2A                          CTI72           

----------------

SCONN10_C12536004_SMLF-CONN,C1A C12536-004               J9B4            

----------------

SCONN11_H67026001_SM-CONN,H670A H67026-001               J8E1            

----------------

SCONN120_A28699018_SM-SCONN,A2A A28699-018               J9B3            

----------------

SCONN120_H61426002_SM-CONN,H61A H61426-002               J4B2            
SCONN120_H61426002_SM-CONN,H61A H61426-002               J4E1            
SCONN120_H61426002_SM-CONN,H61A H61426-002               J6B1            
SCONN120_H61426002_SM-CONN,H61A H61426-002               J6E1            

----------------

SCONN200_H68296001_SM-CONN,H68A H68296-001               J8G1            

----------------

SCONN24_H46321001_SM-SCONN,H46A H46321-001               J8B1            

----------------

SCONN288_H44441003_PIP-SCONN,HA H44441-003               J6L1            
SCONN288_H44441003_PIP-SCONN,HA H44441-003               J6L2            
SCONN288_H44441003_PIP-SCONN,HA H44441-003               J6M1            
SCONN288_H44441003_PIP-SCONN,HA H44441-003               J6T1            
SCONN288_H44441003_PIP-SCONN,HA H44441-003               J6U1            
SCONN288_H44441003_PIP-SCONN,HA H44441-003               J6U2            
SCONN288_H44441003_PIP-SCONN,HA H44441-003               J9L1            
SCONN288_H44441003_PIP-SCONN,HA H44441-003               J9L2            
SCONN288_H44441003_PIP-SCONN,HA H44441-003               J9M1            
SCONN288_H44441003_PIP-SCONN,HA H44441-003               J9T1            
SCONN288_H44441003_PIP-SCONN,HA H44441-003               J9U1            
SCONN288_H44441003_PIP-SCONN,HA H44441-003               J9U2            

----------------

SCONN288_H44441004_PIP-SCONN,HA H44441-004               J1A1            
SCONN288_H44441004_PIP-SCONN,HA H44441-004               J1A2            
SCONN288_H44441004_PIP-SCONN,HA H44441-004               J1B1            
SCONN288_H44441004_PIP-SCONN,HA H44441-004               J1G1            
SCONN288_H44441004_PIP-SCONN,HA H44441-004               J1G2            
SCONN288_H44441004_PIP-SCONN,HA H44441-004               J1G3            
SCONN288_H44441004_PIP-SCONN,HA H44441-004               J4A1            
SCONN288_H44441004_PIP-SCONN,HA H44441-004               J4A2            
SCONN288_H44441004_PIP-SCONN,HA H44441-004               J4B1            
SCONN288_H44441004_PIP-SCONN,HA H44441-004               J4G1            
SCONN288_H44441004_PIP-SCONN,HA H44441-004               J4G2            
SCONN288_H44441004_PIP-SCONN,HA H44441-004               J4G3            

----------------

SCONN3_D53458001_SM-EMPTY,D534A D53458-001               J1B4            

----------------

SCONN60_C21100002_SMLF-CONN,C2A C21100-002               J9A3            

----------------

SCONN64_H87568002_A_SMT-CONN,HA H87568-002               J8E4            

----------------

SCONN75K_H17033002_SMT1-SCONN,A H17033-002               J8F1            

----------------

SCONN80_E67482007_SM-CONN,E674A E67482-007               J8E3            

----------------

SHUNT_SH0201-EMPTY,N_A N_A                      SH3D1           
SHUNT_SH0201-EMPTY,N_A N_A                      SH3D2           
SHUNT_SH0201-EMPTY,N_A N_A                      SH3P1           
SHUNT_SH0201-EMPTY,N_A N_A                      SH3P2           
SHUNT_SH0201-EMPTY,N_A N_A                      SH4L1           
SHUNT_SH0201-EMPTY,N_A N_A                      SH4L2           
SHUNT_SH0201-EMPTY,N_A N_A                      SH4U1           
SHUNT_SH0201-EMPTY,N_A N_A                      SH4U2           
SHUNT_SH0201-EMPTY,N_A N_A                      SH5L1           
SHUNT_SH0201-EMPTY,N_A N_A                      SH5U1           
SHUNT_SH0201-EMPTY,N_A N_A                      SH7L1           
SHUNT_SH0201-EMPTY,N_A N_A                      SH7L2           
SHUNT_SH0201-EMPTY,N_A N_A                      SH7U1           
SHUNT_SH0201-EMPTY,N_A N_A                      SH7U2           
SHUNT_SH0201-EMPTY,N_A N_A                      SH8L1           
SHUNT_SH0201-EMPTY,N_A N_A                      SH8U1           

----------------

SKX_EXT_B_BGA1-IC,TBD TBD                      U2D1            
SKX_EXT_B_BGA1-IC,TBD TBD                      U5D1            

----------------

SLG55021_SM-IC,G56246-001 G56246-001               EU2T1           
SLG55021_SM-IC,G56246-001 G56246-001               EU7E1           
SLG55021_SM-IC,G56246-001 G56246-001               EU8B1           
SLG55021_SM-IC,G56246-001 G56246-001               EU9M1           

----------------

SNLABEL_A_LABEL-EMPTY,N_A N_A                      LB2B1           
SNLABEL_A_LABEL-EMPTY,N_A N_A                      LB2F1           
SNLABEL_A_LABEL-EMPTY,N_A N_A                      LB5B1           
SNLABEL_A_LABEL-EMPTY,N_A N_A                      LB5F1           
SNLABEL_A_LABEL-EMPTY,N_A N_A                      LB6T1           

----------------

SOCKET_P_MECH_A_LEFT-P0,PLASTIA H37604-201               XLU1            
SOCKET_P_MECH_A_LEFT-P0,PLASTIA H37604-201               XLU2            

----------------

SOCKET_P_MECH_A_RIGHT-P0,PLASTA H37604-101               XRU1            
SOCKET_P_MECH_A_RIGHT-P0,PLASTA H37604-101               XRU2            

----------------

SPRINGVILLE_SM1-IC,G47144-004 G47144-004               EU9E1           

----------------

STANDOFF_TH1-SO,H72821-001 H72821-001               RM8D1           

----------------

SWITCH_D37771002_SM-IC,D37771-A D37771-002               S9A1            

----------------

SWITCH_D90553001_SMLF-IC,D9055A D90553-001               S8E1            

----------------

SW_H67881001_SM-IC,H67881-001 H67881-001               S9A2            

----------------

TMP421_TSSOP-IC,G62962-001 G62962-001               U1E1            
TMP421_TSSOP-IC,G62962-001 G62962-001               U9B4            

----------------

TPS2061_SM-IC,H66405-001 H66405-001               U1M3            

----------------

TPS3700_SM-IC,H69492-001 H69492-001               U1D2            
TPS3700_SM-IC,H69492-001 H69492-001               U8D8            
TPS3700_SM-IC,H69492-001 H69492-001               U9P1            
TPS3700_SM-IC,H69492-001 H69492-001               U9P2            

----------------

TPS54821_LCC-IC,H63269-001 H63269-001               EU7E2           

----------------

TTL08_QFN15-74LVC08A,IC,D90404B D90404-001               U8E1            

----------------

TTL1G07_A_SOP-74LVC1G07,IC,C88B C88419-001               U1L4            
TTL1G07_A_SOP-74LVC1G07,IC,C88B C88419-001               U1R1            
TTL1G07_A_SOP-74LVC1G07,IC,C88B C88419-001               U2P1            
TTL1G07_A_SOP-74LVC1G07,IC,C88B C88419-001               U8D2            
TTL1G07_A_SOP-74LVC1G07,IC,C88B C88419-001               U8D3            
TTL1G07_A_SOP-74LVC1G07,IC,C88B C88419-001               U8G2            
TTL1G07_A_SOP-74LVC1G07,IC,C88B C88419-001               U8G3            
TTL1G07_A_SOP-74LVC1G07,IC,C88B C88419-001               U9A1            
TTL1G07_A_SOP-74LVC1G07,IC,C88B C88419-001               U9F3            

----------------

TTL1G08_SOTLF-NC7SZ08,IC,D1032B D10321-001               U1E2            
TTL1G08_SOTLF-NC7SZ08,IC,D1032B D10321-001               U7E2            
TTL1G08_SOTLF-NC7SZ08,IC,D1032B D10321-001               U7E3            

----------------

TTL1G08_SOTLF-NC7SZ08,IC,D1032C D10321-001               U1M1            

----------------

TTL1G126_A_SOT-74HC1G126,IC,A7B A79322-001               U1D1            
TTL1G126_A_SOT-74HC1G126,IC,A7B A79322-001               U1R2            
TTL1G126_A_SOT-74HC1G126,IC,A7B A79322-001               U8D5            
TTL1G126_A_SOT-74HC1G126,IC,A7B A79322-001               U8E3            
TTL1G126_A_SOT-74HC1G126,IC,A7B A79322-001               U8E4            

----------------

TTL1G32_A_SOT-74LVC1G32,IC,E60B E60229-001               U2T2            
TTL1G32_A_SOT-74LVC1G32,IC,E60B E60229-001               U2T3            

----------------

TTL1G86_SOTLF-74AHCT1G86,IC,D3B D39848-001               U1L2            

----------------

TTL2G07_SOT23LF-74LVC2G07,IC,DB D22707-001               U8F3            
TTL2G07_SOT23LF-74LVC2G07,IC,DB D22707-001               U8G1            

----------------

TTL2G14_SMLF-74LVC2G14,IC,D184B D18476-001               U2R1            
TTL2G14_SMLF-74LVC2G14,IC,D184B D18476-001               U9A3            
TTL2G14_SMLF-74LVC2G14,IC,D184B D18476-001               U9A4            

----------------

TTL3126_QFNLF-74CBTLV3126,IC,DB D18317-001               U1L1            
TTL3126_QFNLF-74CBTLV3126,IC,DB D18317-001               U1L5            

----------------

VERT_BATT_3PIN_PIP-3PVERT,C686A C68619-005               XBT8G1          

----------------

W25Q128_SKT16-IC,H12709-001 H12709-001               U8F2            

----------------

W25Q256_XSOI-IC,H25002-001 H25002-001               U3T1            
W25Q256_XSOI-IC,H25002-001 H25002-001               U7F1            

----------------

ZENER_SM-13V,IC,H69095-001 H69095-001               VR1D1           

----------------

END STUFF LIST
